FILE_TYPE = MACRO_DRAWING;
SET COLOR_WIRE YELLOW;
SET COLOR_PROP ORANGE;
SET COLOR_DOT WHITE;
SET COLOR_ARC YELLOW;
SET COLOR_BODY GREEN;
SET COLOR_NOTE PURPLE;
SET PROP_DISPLAY VALUE;
SET PAGE_NUMBER P169;
FORCEADD OFFPAGE..1
(-8225 1500);
FORCEPROP 2 LAST $XR5 199 
J 0
(-9077 1500);
DISPLAY 0.638298 (-9077 1500);
PAINT MONO (-9077 1500);
FORCEPROP 2 LAST $XR4 198 
J 0
(-8957 1500);
DISPLAY 0.638298 (-8957 1500);
PAINT MONO (-8957 1500);
FORCEPROP 2 LAST $XR3 196 
J 0
(-8837 1500);
DISPLAY 0.638298 (-8837 1500);
PAINT MONO (-8837 1500);
FORCEPROP 2 LAST $XR2 195 
J 0
(-8717 1500);
DISPLAY 0.638298 (-8717 1500);
PAINT MONO (-8717 1500);
FORCEPROP 2 LAST $XR1 194 
J 0
(-8597 1500);
DISPLAY 0.638298 (-8597 1500);
PAINT MONO (-8597 1500);
FORCEPROP 2 LAST $XR0 193 
J 0
(-8477 1500);
DISPLAY 0.638298 (-8477 1500);
PAINT MONO (-8477 1500);
FORCEPROP 2 LAST CDS_LIB standard
J 0
(-8225 1500);
DISPLAY INVISIBLE (-8225 1500);
FORCEPROP 1 LAST OFFPAGE TRUE
J 0
(-7900 1375);
DISPLAY 0.872340 (-7900 1375);
PAINT GREEN (-7900 1375);
DISPLAY INVISIBLE (-7900 1375);
FORCEPROP 1 LAST COMMENT_BODY TRUE
J 0
(-8100 1400);
DISPLAY 0.872340 (-8100 1400);
PAINT GREEN (-8100 1400);
DISPLAY INVISIBLE (-8100 1400);
FORCEPROP 2 LAST PATH I1
J 0
(-8475 1550);
DISPLAY 0.680851 (-8475 1550);
DISPLAY INVISIBLE (-8475 1550);
FORCEADD Q_RES..1
(-7350 1300);
FORCEPROP 1 LAST LOCATION PR321
J 0
(-7400 1350);
DISPLAY 0.489362 (-7400 1350);
PAINT SKYBLUE (-7400 1350);
FORCEPROP 0 LAST $SEC 1
J 0
(-7350 1375);
DISPLAY 0.680851 (-7350 1375);
PAINT MONO (-7350 1375);
DISPLAY INVISIBLE (-7350 1375);
FORCEPROP 0 LAST CDS_SEC 1
J 0
(-7350 1375);
DISPLAY 1.021277 (-7350 1375);
DISPLAY INVISIBLE (-7350 1375);
FORCEPROP 1 LASTPIN (-7450 1300) $PN 1
J 0
(-7438 1312);
DISPLAY 0.489362 (-7438 1312);
PAINT MONO (-7438 1312);
FORCEPROP 1 LASTPIN (-7250 1300) $PN 2
J 0
(-7288 1312);
DISPLAY 0.489362 (-7288 1312);
PAINT MONO (-7288 1312);
FORCEPROP 1 LAST PACK_TYPE 0402LF
J 0
(-7250 1250);
DISPLAY 0.489362 (-7250 1250);
PAINT SKYBLUE (-7250 1250);
FORCEPROP 1 LAST WATTAGE 1/16W
J 0
(-7250 1200);
DISPLAY 0.489362 (-7250 1200);
PAINT SKYBLUE (-7250 1200);
FORCEPROP 1 LAST MATERIAL EMPTY
J 0
(-7550 1200);
DISPLAY 0.489362 (-7550 1200);
PAINT RED (-7550 1200);
FORCEPROP 1 LAST TOLERANCE 1%
J 0
(-7225 1325);
DISPLAY 0.489362 (-7225 1325);
PAINT SKYBLUE (-7225 1325);
FORCEPROP 1 LAST VALUE 8.87K
J 2
(-7450 1325);
DISPLAY 0.489362 (-7450 1325);
PAINT SKYBLUE (-7450 1325);
FORCEPROP 2 LAST CDS_LIB pure_quanta
J 0
(-7350 1300);
DISPLAY INVISIBLE (-7350 1300);
FORCEPROP 1 LAST PATH I10
J 0
(-7400 1450);
DISPLAY 0.978723 (-7400 1450);
PAINT WHITE (-7400 1450);
DISPLAY INVISIBLE (-7400 1450);
FORCEPROP 1 LAST PART_NUMBER CS28872FB01
J 0
(-7625 1250);
DISPLAY 0.489362 (-7625 1250);
PAINT SKYBLUE (-7625 1250);
DISPLAY INVISIBLE (-7625 1250);
FORCEADD OFFPAGE..2
R 2
(-7300 1100);
FORCEPROP 2 LAST $XR3 193 
J 0
(-7825 1064);
DISPLAY 0.638298 (-7825 1064);
PAINT MONO (-7825 1064);
FORCEPROP 2 LAST $XR2 196 
J 0
(-7705 1064);
DISPLAY 0.638298 (-7705 1064);
PAINT MONO (-7705 1064);
FORCEPROP 2 LAST $XR1 195 
J 0
(-7585 1064);
DISPLAY 0.638298 (-7585 1064);
PAINT MONO (-7585 1064);
FORCEPROP 2 LAST $XR0 194 
J 0
(-7585 1100);
DISPLAY 0.638298 (-7585 1100);
PAINT MONO (-7585 1100);
FORCEPROP 2 LAST CDS_LIB standard
J 0
(-7300 1100);
DISPLAY INVISIBLE (-7300 1100);
FORCEPROP 1 LAST OFFPAGE TRUE
J 2
(-7625 975);
DISPLAY 0.872340 (-7625 975);
PAINT GREEN (-7625 975);
DISPLAY INVISIBLE (-7625 975);
FORCEPROP 1 LAST COMMENT_BODY TRUE
J 2
(-7255 1005);
DISPLAY 0.872340 (-7255 1005);
PAINT GREEN (-7255 1005);
DISPLAY INVISIBLE (-7255 1005);
FORCEPROP 2 LAST PATH I11
J 0
(-7575 1150);
DISPLAY 0.680851 (-7575 1150);
DISPLAY INVISIBLE (-7575 1150);
FORCEADD OFFPAGE..1
(-7275 1000);
FORCEPROP 2 LAST $XR0 193 
J 0
(-7527 1000);
DISPLAY 0.638298 (-7527 1000);
PAINT MONO (-7527 1000);
FORCEPROP 2 LAST CDS_LIB standard
J 2
(-7275 1000);
DISPLAY INVISIBLE (-7275 1000);
FORCEPROP 1 LAST OFFPAGE TRUE
J 0
(-6950 875);
DISPLAY 0.872340 (-6950 875);
PAINT GREEN (-6950 875);
DISPLAY INVISIBLE (-6950 875);
FORCEPROP 1 LAST COMMENT_BODY TRUE
J 0
(-7150 900);
DISPLAY 0.872340 (-7150 900);
PAINT GREEN (-7150 900);
DISPLAY INVISIBLE (-7150 900);
FORCEPROP 2 LAST PATH I12
J 0
(-7550 1050);
DISPLAY 0.680851 (-7550 1050);
DISPLAY INVISIBLE (-7550 1050);
FORCEADD OFFPAGE..2
R 2
(-7325 1600);
FORCEPROP 2 LAST $XR0 193 
J 0
(-7580 1600);
DISPLAY 0.638298 (-7580 1600);
PAINT MONO (-7580 1600);
FORCEPROP 2 LAST CDS_LIB standard
J 2
(-7325 1600);
DISPLAY INVISIBLE (-7325 1600);
FORCEPROP 1 LAST OFFPAGE TRUE
J 2
(-7650 1475);
DISPLAY 0.872340 (-7650 1475);
PAINT GREEN (-7650 1475);
DISPLAY INVISIBLE (-7650 1475);
FORCEPROP 1 LAST COMMENT_BODY TRUE
J 2
(-7280 1505);
DISPLAY 0.872340 (-7280 1505);
PAINT GREEN (-7280 1505);
DISPLAY INVISIBLE (-7280 1505);
FORCEPROP 2 LAST PATH I13
J 0
(-7600 1650);
DISPLAY 0.680851 (-7600 1650);
DISPLAY INVISIBLE (-7600 1650);
FORCEADD Q_CAP..1
(-7650 1950);
FORCEPROP 1 LAST LOCATION PC476
J 0
(-7600 2050);
DISPLAY 0.489362 (-7600 2050);
PAINT SKYBLUE (-7600 2050);
FORCEPROP 0 LAST $SEC 1
J 0
(-7600 2100);
DISPLAY 0.680851 (-7600 2100);
PAINT MONO (-7600 2100);
DISPLAY INVISIBLE (-7600 2100);
FORCEPROP 0 LAST CDS_SEC 1
J 0
(-7600 2100);
DISPLAY 1.021277 (-7600 2100);
DISPLAY INVISIBLE (-7600 2100);
FORCEPROP 1 LASTPIN (-7650 2050) $PN 1
J 0
(-7640 2030);
DISPLAY 0.489362 (-7640 2030);
PAINT MONO (-7640 2030);
FORCEPROP 1 LASTPIN (-7650 1850) $PN 2
J 0
(-7640 1830);
DISPLAY 0.489362 (-7640 1830);
PAINT MONO (-7640 1830);
FORCEPROP 1 LAST PACK_TYPE C0402
J 0
(-7600 1750);
DISPLAY 0.489362 (-7600 1750);
PAINT SKYBLUE (-7600 1750);
FORCEPROP 1 LAST VOLTAGE 10V
J 0
(-7600 1950);
DISPLAY 0.489362 (-7600 1950);
PAINT SKYBLUE (-7600 1950);
FORCEPROP 1 LAST VALUE 2.2UF
J 0
(-7600 2000);
DISPLAY 0.489362 (-7600 2000);
PAINT SKYBLUE (-7600 2000);
FORCEPROP 1 LAST TOLERANCE 10%
J 0
(-7600 1900);
DISPLAY 0.489362 (-7600 1900);
PAINT SKYBLUE (-7600 1900);
FORCEPROP 1 LAST MATERIAL X6S
J 0
(-7600 1850);
DISPLAY 0.489362 (-7600 1850);
PAINT SKYBLUE (-7600 1850);
FORCEPROP 2 LAST CDS_LIB pure_quanta
J 0
(-7650 1950);
DISPLAY INVISIBLE (-7650 1950);
FORCEPROP 1 LAST PATH I14
J 0
(-7600 2100);
DISPLAY 0.978723 (-7600 2100);
PAINT WHITE (-7600 2100);
DISPLAY INVISIBLE (-7600 2100);
FORCEPROP 1 LAST PART_NUMBER CH5222KEB01
J 0
(-7600 1800);
DISPLAY 0.489362 (-7600 1800);
PAINT SKYBLUE (-7600 1800);
DISPLAY INVISIBLE (-7600 1800);
FORCEADD UNIVERSAL_GND..1
(-7650 1750);
FORCEPROP 3 LASTPIN (-7650 1800) SIG_NAME GND\g
J 0
(-7640 1810);
DISPLAY 0.659574 (-7640 1810);
PAINT MONO (-7640 1810);
DISPLAY INVISIBLE (-7640 1810);
FORCEPROP 2 LAST CDS_LIB pure_quanta_power
J 0
(-7650 1750);
DISPLAY INVISIBLE (-7650 1750);
FORCEPROP 1 LAST HDL_POWER GND
J 1
(-7625 1675);
DISPLAY 0.872340 (-7625 1675);
PAINT GREEN (-7625 1675);
DISPLAY INVISIBLE (-7625 1675);
FORCEPROP 1 LAST PATH I15
J 0
(-7575 1750);
DISPLAY 0.872340 (-7575 1750);
PAINT AQUA (-7575 1750);
DISPLAY INVISIBLE (-7575 1750);
FORCEADD ISL99390FRZTR5935..1
(-6175 1600);
FORCEPROP 1 LAST LOCATION PU43
J 0
(-6475 2475);
DISPLAY 0.489362 (-6475 2475);
PAINT SKYBLUE (-6475 2475);
FORCEPROP 0 LAST $SEC 1
J 0
(-6475 2625);
DISPLAY 0.680851 (-6475 2625);
PAINT MONO (-6475 2625);
DISPLAY INVISIBLE (-6475 2625);
FORCEPROP 0 LAST CDS_SEC 1
J 0
(-6475 2625);
DISPLAY 1.021277 (-6475 2625);
DISPLAY INVISIBLE (-6475 2625);
FORCEPROP 0 LASTPIN (-5775 1150) $PN 2
J 0
(-5765 1160);
DISPLAY 0.489362 (-5765 1160);
PAINT MONO (-5765 1160);
FORCEPROP 0 LASTPIN (-5775 1950) $PN 33
J 0
(-5765 1960);
DISPLAY 0.489362 (-5765 1960);
PAINT MONO (-5765 1960);
FORCEPROP 0 LASTPIN (-6625 1350) $PN 31
J 2
(-6635 1360);
DISPLAY 0.489362 (-6635 1360);
PAINT MONO (-6635 1360);
FORCEPROP 0 LASTPIN (-6625 1750) $PN 35
J 2
(-6635 1760);
DISPLAY 0.489362 (-6635 1760);
PAINT MONO (-6635 1760);
FORCEPROP 0 LASTPIN (-5775 1300) $PN 6
J 0
(-5765 1310);
DISPLAY 0.489362 (-5765 1310);
PAINT MONO (-5765 1310);
FORCEPROP 0 LASTPIN (-5775 1250) $PN 41
J 0
(-5765 1260);
DISPLAY 0.489362 (-5765 1260);
PAINT MONO (-5765 1260);
FORCEPROP 0 LASTPIN (-6625 1600) $PN 38
J 2
(-6635 1610);
DISPLAY 0.489362 (-6635 1610);
PAINT MONO (-6635 1610);
FORCEPROP 0 LASTPIN (-6625 1300) $PN 37
J 2
(-6635 1310);
DISPLAY 0.489362 (-6635 1310);
PAINT MONO (-6635 1310);
FORCEPROP 0 LASTPIN (-5775 1100) $PN 5
J 0
(-5765 1110);
DISPLAY 0.489362 (-5765 1110);
PAINT MONO (-5765 1110);
FORCEPROP 0 LASTPIN (-5775 1050) $PN 7_9-20_24
J 0
(-5765 1060);
DISPLAY 0.489362 (-5765 1060);
PAINT MONO (-5765 1060);
FORCEPROP 0 LASTPIN (-5775 1000) $PN 40
J 0
(-5765 1010);
DISPLAY 0.489362 (-5765 1010);
PAINT MONO (-5765 1010);
FORCEPROP 0 LASTPIN (-5775 1700) $PN 32
J 0
(-5765 1710);
DISPLAY 0.489362 (-5765 1710);
PAINT MONO (-5765 1710);
FORCEPROP 0 LASTPIN (-6625 2250) $PN 4
J 2
(-6635 2260);
DISPLAY 0.489362 (-6635 2260);
PAINT MONO (-6635 2260);
FORCEPROP 0 LASTPIN (-6625 1000) $PN 34
J 2
(-6635 1010);
DISPLAY 0.489362 (-6635 1010);
PAINT MONO (-6635 1010);
FORCEPROP 0 LASTPIN (-6625 1500) $PN 39
J 2
(-6635 1510);
DISPLAY 0.489362 (-6635 1510);
PAINT MONO (-6635 1510);
FORCEPROP 0 LASTPIN (-5775 1600) $PN 10_19
J 0
(-5765 1610);
DISPLAY 0.489362 (-5765 1610);
PAINT MONO (-5765 1610);
FORCEPROP 0 LASTPIN (-6625 1100) $PN 36
J 2
(-6635 1110);
DISPLAY 0.489362 (-6635 1110);
PAINT MONO (-6635 1110);
FORCEPROP 0 LASTPIN (-6625 1950) $PN 3
J 2
(-6635 1960);
DISPLAY 0.489362 (-6635 1960);
PAINT MONO (-6635 1960);
FORCEPROP 0 LASTPIN (-5775 2250) $PN 25_29
J 0
(-5765 2260);
DISPLAY 0.489362 (-5765 2260);
PAINT MONO (-5765 2260);
FORCEPROP 0 LASTPIN (-5775 2200) $PN 30
J 0
(-5765 2210);
DISPLAY 0.489362 (-5765 2210);
PAINT MONO (-5765 2210);
FORCEPROP 0 LASTPIN (-5775 1350) $PN 1
J 0
(-5765 1360);
DISPLAY 0.489362 (-5765 1360);
PAINT MONO (-5765 1360);
FORCEPROP 1 LAST MATERIAL IC
J 0
(-6475 2325);
DISPLAY 0.489362 (-6475 2325);
PAINT SKYBLUE (-6475 2325);
FORCEPROP 2 LAST VALUE ISL99390FRZ-TR5935
J 0
(-6475 2525);
DISPLAY 0.489362 (-6475 2525);
PAINT SKYBLUE (-6475 2525);
FORCEPROP 2 LAST PART_TYPE SMLF
J 0
(-6475 2575);
DISPLAY 1.021277 (-6475 2575);
FORCEPROP 1 LAST CDS_LMAN_SYM_OUTLINE -300,700,250,-650
J 0
(-6175 1600);
DISPLAY 0.468085 (-6175 1600);
PAINT GREEN (-6175 1600);
DISPLAY INVISIBLE (-6175 1600);
FORCEPROP 2 LAST CDS_LIB pure_quanta
J 0
(-6175 1600);
DISPLAY INVISIBLE (-6175 1600);
FORCEPROP 1 LAST NEEDS_NO_SIZE TRUE
J 0
(-6175 1600);
DISPLAY 0.723404 (-6175 1600);
PAINT GREEN (-6175 1600);
DISPLAY INVISIBLE (-6175 1600);
FORCEPROP 1 LAST PATH I16
J 0
(-6175 1600);
DISPLAY 0.723404 (-6175 1600);
PAINT GREEN (-6175 1600);
DISPLAY INVISIBLE (-6175 1600);
FORCEPROP 1 LAST PART_NUMBER AL099390004
J 0
(-6475 2400);
DISPLAY 0.489362 (-6475 2400);
PAINT SKYBLUE (-6475 2400);
DISPLAY INVISIBLE (-6475 2400);
FORCEADD Q_RES..2
(-7650 2450);
FORCEPROP 1 LAST LOCATION PR319
J 0
(-7605 2575);
DISPLAY 0.489362 (-7605 2575);
PAINT SKYBLUE (-7605 2575);
FORCEPROP 0 LAST $SEC 1
J 0
(-7600 2625);
DISPLAY 0.680851 (-7600 2625);
PAINT MONO (-7600 2625);
DISPLAY INVISIBLE (-7600 2625);
FORCEPROP 0 LAST CDS_SEC 1
J 0
(-7600 2625);
DISPLAY 1.021277 (-7600 2625);
DISPLAY INVISIBLE (-7600 2625);
FORCEPROP 1 LASTPIN (-7650 2550) $PN 1
J 0
(-7645 2512);
DISPLAY 0.489362 (-7645 2512);
PAINT MONO (-7645 2512);
FORCEPROP 1 LASTPIN (-7650 2350) $PN 2
J 0
(-7645 2360);
DISPLAY 0.489362 (-7645 2360);
PAINT MONO (-7645 2360);
FORCEPROP 1 LAST PACK_TYPE 0402LF
J 0
(-7600 2275);
DISPLAY 0.489362 (-7600 2275);
PAINT SKYBLUE (-7600 2275);
FORCEPROP 1 LAST VALUE 2.2
J 0
(-7600 2525);
DISPLAY 0.489362 (-7600 2525);
PAINT SKYBLUE (-7600 2525);
FORCEPROP 1 LAST WATTAGE 1/16W
J 0
(-7600 2425);
DISPLAY 0.489362 (-7600 2425);
PAINT SKYBLUE (-7600 2425);
FORCEPROP 1 LAST MATERIAL CHIP
J 0
(-7600 2375);
DISPLAY 0.489362 (-7600 2375);
PAINT SKYBLUE (-7600 2375);
FORCEPROP 1 LAST TOLERANCE 1%
J 0
(-7600 2475);
DISPLAY 0.489362 (-7600 2475);
PAINT SKYBLUE (-7600 2475);
FORCEPROP 2 LAST CDS_LIB pure_quanta
J 0
(-7650 2450);
DISPLAY INVISIBLE (-7650 2450);
FORCEPROP 1 LAST PATH I17
J 0
(-7600 2625);
DISPLAY 0.978723 (-7600 2625);
PAINT WHITE (-7600 2625);
DISPLAY INVISIBLE (-7600 2625);
FORCEPROP 1 LAST PART_NUMBER CS-2202FB01
J 0
(-7600 2325);
DISPLAY 0.489362 (-7600 2325);
PAINT SKYBLUE (-7600 2325);
DISPLAY INVISIBLE (-7600 2325);
FORCEADD UNIVERSAL_GND..1
(-7300 2200);
FORCEPROP 3 LASTPIN (-7300 2250) SIG_NAME GND\g
J 0
(-7290 2260);
DISPLAY 0.659574 (-7290 2260);
PAINT MONO (-7290 2260);
DISPLAY INVISIBLE (-7290 2260);
FORCEPROP 2 LAST CDS_LIB pure_quanta_power
J 0
(-7300 2200);
DISPLAY INVISIBLE (-7300 2200);
FORCEPROP 1 LAST HDL_POWER GND
J 1
(-7275 2125);
DISPLAY 0.872340 (-7275 2125);
PAINT GREEN (-7275 2125);
DISPLAY INVISIBLE (-7275 2125);
FORCEPROP 1 LAST PATH I18
J 0
(-7225 2200);
DISPLAY 0.872340 (-7225 2200);
PAINT AQUA (-7225 2200);
DISPLAY INVISIBLE (-7225 2200);
FORCEADD Q_CAP..1
(-7300 2475);
FORCEPROP 1 LAST LOCATION PC478_C0P0_2
J 0
(-7250 2575);
DISPLAY 0.489362 (-7250 2575);
PAINT SKYBLUE (-7250 2575);
FORCEPROP 0 LAST $SEC 1
J 0
(-7250 2625);
DISPLAY 0.680851 (-7250 2625);
PAINT MONO (-7250 2625);
DISPLAY INVISIBLE (-7250 2625);
FORCEPROP 0 LAST CDS_SEC 1
J 0
(-7250 2625);
DISPLAY 1.021277 (-7250 2625);
DISPLAY INVISIBLE (-7250 2625);
FORCEPROP 1 LASTPIN (-7300 2575) $PN 1
J 0
(-7290 2555);
DISPLAY 0.489362 (-7290 2555);
PAINT MONO (-7290 2555);
FORCEPROP 1 LASTPIN (-7300 2375) $PN 2
J 0
(-7290 2355);
DISPLAY 0.489362 (-7290 2355);
PAINT MONO (-7290 2355);
FORCEPROP 1 LAST VOLTAGE 10V
J 0
(-7250 2475);
DISPLAY 0.489362 (-7250 2475);
PAINT SKYBLUE (-7250 2475);
FORCEPROP 1 LAST VALUE 2.2UF
J 0
(-7250 2525);
DISPLAY 0.489362 (-7250 2525);
PAINT SKYBLUE (-7250 2525);
FORCEPROP 1 LAST PACK_TYPE C0402
J 0
(-7250 2275);
DISPLAY 0.489362 (-7250 2275);
PAINT SKYBLUE (-7250 2275);
FORCEPROP 1 LAST TOLERANCE 10%
J 0
(-7250 2425);
DISPLAY 0.489362 (-7250 2425);
PAINT SKYBLUE (-7250 2425);
FORCEPROP 1 LAST MATERIAL X6S
J 0
(-7250 2375);
DISPLAY 0.489362 (-7250 2375);
PAINT SKYBLUE (-7250 2375);
FORCEPROP 2 LAST CDS_LIB pure_quanta
J 0
(-7300 2475);
DISPLAY INVISIBLE (-7300 2475);
FORCEPROP 1 LAST PATH I19
J 0
(-7250 2625);
DISPLAY 0.978723 (-7250 2625);
PAINT WHITE (-7250 2625);
DISPLAY INVISIBLE (-7250 2625);
FORCEPROP 1 LAST PART_NUMBER CH5222KEB01
J 0
(-7250 2325);
DISPLAY 0.489362 (-7250 2325);
PAINT SKYBLUE (-7250 2325);
DISPLAY INVISIBLE (-7250 2325);
FORCEADD OFFPAGE..1
(-8250 4250);
FORCEPROP 2 LAST $XR5 199 
J 0
(-9132 4250);
DISPLAY 0.638298 (-9132 4250);
PAINT MONO (-9132 4250);
FORCEPROP 2 LAST $XR4 198 
J 0
(-9012 4250);
DISPLAY 0.638298 (-9012 4250);
PAINT MONO (-9012 4250);
FORCEPROP 2 LAST $XR3 196 
J 0
(-8892 4250);
DISPLAY 0.638298 (-8892 4250);
PAINT MONO (-8892 4250);
FORCEPROP 2 LAST $XR2 195 
J 0
(-8772 4250);
DISPLAY 0.638298 (-8772 4250);
PAINT MONO (-8772 4250);
FORCEPROP 2 LAST $XR1 194 
J 0
(-8652 4250);
DISPLAY 0.638298 (-8652 4250);
PAINT MONO (-8652 4250);
FORCEPROP 2 LAST $XR0 193 
J 0
(-8532 4250);
DISPLAY 0.638298 (-8532 4250);
PAINT MONO (-8532 4250);
FORCEPROP 2 LAST CDS_LIB standard
J 0
(-8250 4250);
DISPLAY INVISIBLE (-8250 4250);
FORCEPROP 1 LAST OFFPAGE TRUE
J 0
(-7925 4125);
DISPLAY 0.872340 (-7925 4125);
PAINT GREEN (-7925 4125);
DISPLAY INVISIBLE (-7925 4125);
FORCEPROP 1 LAST COMMENT_BODY TRUE
J 0
(-8125 4150);
DISPLAY 0.872340 (-8125 4150);
PAINT GREEN (-8125 4150);
DISPLAY INVISIBLE (-8125 4150);
FORCEPROP 2 LAST PATH I2
J 0
(-8500 4300);
DISPLAY 0.680851 (-8500 4300);
DISPLAY INVISIBLE (-8500 4300);
FORCEADD VCC_CORE..1
(-7650 2850);
FORCEPROP 3 LASTPIN (-7650 2800) SIG_NAME PVDDCR_CPU0_P0_PVCC\g
J 0
(-7640 2810);
DISPLAY 0.659574 (-7640 2810);
PAINT MONO (-7640 2810);
DISPLAY INVISIBLE (-7640 2810);
FORCEPROP 1 LAST HDL_POWER PVDDCR_CPU0_P0_PVCC
J 1
(-7650 2900);
DISPLAY 0.489362 (-7650 2900);
PAINT GREEN (-7650 2900);
FORCEPROP 2 LAST CDS_LIB pure_quanta_power
J 0
(-7650 2850);
DISPLAY INVISIBLE (-7650 2850);
FORCEPROP 1 LAST PATH I20
J 0
(-7600 2875);
DISPLAY 0.872340 (-7600 2875);
PAINT AQUA (-7600 2875);
DISPLAY INVISIBLE (-7600 2875);
FORCEADD UNIVERSAL_GND..1
(-8025 3800);
FORCEPROP 3 LASTPIN (-8025 3850) SIG_NAME GND\g
J 0
(-8015 3860);
DISPLAY 0.659574 (-8015 3860);
PAINT MONO (-8015 3860);
DISPLAY INVISIBLE (-8015 3860);
FORCEPROP 2 LAST CDS_LIB pure_quanta_power
J 0
(-8025 3800);
DISPLAY INVISIBLE (-8025 3800);
FORCEPROP 1 LAST HDL_POWER GND
J 1
(-8000 3725);
DISPLAY 0.872340 (-8000 3725);
PAINT GREEN (-8000 3725);
DISPLAY INVISIBLE (-8000 3725);
FORCEPROP 1 LAST PATH I21
J 0
(-7950 3800);
DISPLAY 0.872340 (-7950 3800);
PAINT AQUA (-7950 3800);
DISPLAY INVISIBLE (-7950 3800);
FORCEADD Q_CAP..1
(-8025 4075);
FORCEPROP 1 LAST LOCATION PC473_1
J 0
(-7975 4175);
DISPLAY 0.489362 (-7975 4175);
PAINT SKYBLUE (-7975 4175);
FORCEPROP 0 LAST $SEC 1
J 0
(-7975 4200);
DISPLAY 0.680851 (-7975 4200);
PAINT MONO (-7975 4200);
DISPLAY INVISIBLE (-7975 4200);
FORCEPROP 0 LAST CDS_SEC 1
J 0
(-7975 4200);
DISPLAY 1.021277 (-7975 4200);
DISPLAY INVISIBLE (-7975 4200);
FORCEPROP 1 LASTPIN (-8025 4175) $PN 1
J 0
(-8015 4155);
DISPLAY 0.489362 (-8015 4155);
PAINT MONO (-8015 4155);
FORCEPROP 1 LASTPIN (-8025 3975) $PN 2
J 0
(-8015 3955);
DISPLAY 0.489362 (-8015 3955);
PAINT MONO (-8015 3955);
FORCEPROP 1 LAST PACK_TYPE 0402
J 0
(-7975 3875);
DISPLAY 0.489362 (-7975 3875);
PAINT SKYBLUE (-7975 3875);
FORCEPROP 1 LAST VOLTAGE 25V
J 0
(-7975 4075);
DISPLAY 0.489362 (-7975 4075);
PAINT SKYBLUE (-7975 4075);
FORCEPROP 1 LAST TOLERANCE 10%
J 0
(-7975 4025);
DISPLAY 0.489362 (-7975 4025);
PAINT SKYBLUE (-7975 4025);
FORCEPROP 1 LAST MATERIAL X7R
J 0
(-7975 3975);
DISPLAY 0.489362 (-7975 3975);
PAINT SKYBLUE (-7975 3975);
FORCEPROP 1 LAST VALUE 0.1UF
J 0
(-7975 4125);
DISPLAY 0.489362 (-7975 4125);
PAINT SKYBLUE (-7975 4125);
FORCEPROP 2 LAST CDS_LIB pure_quanta
J 0
(-8025 4075);
DISPLAY INVISIBLE (-8025 4075);
FORCEPROP 1 LAST PATH I22
J 0
(-7975 4225);
DISPLAY 0.978723 (-7975 4225);
PAINT WHITE (-7975 4225);
DISPLAY INVISIBLE (-7975 4225);
FORCEPROP 1 LAST PART_NUMBER CH4104K1B00
J 0
(-7975 3925);
DISPLAY 0.489362 (-7975 3925);
PAINT SKYBLUE (-7975 3925);
DISPLAY INVISIBLE (-7975 3925);
FORCEADD OFFPAGE..1
(-7300 3750);
FORCEPROP 2 LAST $XR0 193 
J 0
(-7552 3750);
DISPLAY 0.638298 (-7552 3750);
PAINT MONO (-7552 3750);
FORCEPROP 2 LAST CDS_LIB standard
J 2
(-7300 3750);
DISPLAY INVISIBLE (-7300 3750);
FORCEPROP 1 LAST OFFPAGE TRUE
J 0
(-6975 3625);
DISPLAY 0.872340 (-6975 3625);
PAINT GREEN (-6975 3625);
DISPLAY INVISIBLE (-6975 3625);
FORCEPROP 1 LAST COMMENT_BODY TRUE
J 0
(-7175 3650);
DISPLAY 0.872340 (-7175 3650);
PAINT GREEN (-7175 3650);
DISPLAY INVISIBLE (-7175 3650);
FORCEPROP 2 LAST PATH I23
J 0
(-7550 3800);
DISPLAY 0.680851 (-7550 3800);
DISPLAY INVISIBLE (-7550 3800);
FORCEADD UNIVERSAL_GND..1
(-7675 3875);
FORCEPROP 3 LASTPIN (-7675 3925) SIG_NAME GND\g
J 0
(-7665 3935);
DISPLAY 0.659574 (-7665 3935);
PAINT MONO (-7665 3935);
DISPLAY INVISIBLE (-7665 3935);
FORCEPROP 2 LAST CDS_LIB pure_quanta_power
J 0
(-7675 3875);
DISPLAY INVISIBLE (-7675 3875);
FORCEPROP 1 LAST HDL_POWER GND
J 1
(-7650 3800);
DISPLAY 0.872340 (-7650 3800);
PAINT GREEN (-7650 3800);
DISPLAY INVISIBLE (-7650 3800);
FORCEPROP 1 LAST PATH I24
J 0
(-7600 3875);
DISPLAY 0.872340 (-7600 3875);
PAINT AQUA (-7600 3875);
DISPLAY INVISIBLE (-7600 3875);
FORCEADD OFFPAGE..2
R 2
(-7325 3850);
FORCEPROP 2 LAST $XR3 193 
J 0
(-7820 3814);
DISPLAY 0.638298 (-7820 3814);
PAINT MONO (-7820 3814);
FORCEPROP 2 LAST $XR2 196 
J 0
(-7700 3814);
DISPLAY 0.638298 (-7700 3814);
PAINT MONO (-7700 3814);
FORCEPROP 2 LAST $XR1 195 
J 0
(-7580 3814);
DISPLAY 0.638298 (-7580 3814);
PAINT MONO (-7580 3814);
FORCEPROP 2 LAST $XR0 194 
J 0
(-7580 3850);
DISPLAY 0.638298 (-7580 3850);
PAINT MONO (-7580 3850);
FORCEPROP 2 LAST CDS_LIB standard
J 0
(-7325 3850);
DISPLAY INVISIBLE (-7325 3850);
FORCEPROP 1 LAST OFFPAGE TRUE
J 2
(-7650 3725);
DISPLAY 0.872340 (-7650 3725);
PAINT GREEN (-7650 3725);
DISPLAY INVISIBLE (-7650 3725);
FORCEPROP 1 LAST COMMENT_BODY TRUE
J 2
(-7280 3755);
DISPLAY 0.872340 (-7280 3755);
PAINT GREEN (-7280 3755);
DISPLAY INVISIBLE (-7280 3755);
FORCEPROP 2 LAST PATH I25
J 0
(-7600 3900);
DISPLAY 0.680851 (-7600 3900);
DISPLAY INVISIBLE (-7600 3900);
FORCEADD ISL99390FRZTR5935..1
(-6200 4350);
FORCEPROP 1 LAST LOCATION PU6
J 0
(-6500 5225);
DISPLAY 0.489362 (-6500 5225);
PAINT SKYBLUE (-6500 5225);
FORCEPROP 0 LAST $SEC 1
J 0
(-6500 5375);
DISPLAY 0.680851 (-6500 5375);
PAINT MONO (-6500 5375);
DISPLAY INVISIBLE (-6500 5375);
FORCEPROP 0 LAST CDS_SEC 1
J 0
(-6500 5375);
DISPLAY 1.021277 (-6500 5375);
DISPLAY INVISIBLE (-6500 5375);
FORCEPROP 0 LASTPIN (-5800 3900) $PN 2
J 0
(-5790 3910);
DISPLAY 0.489362 (-5790 3910);
PAINT MONO (-5790 3910);
FORCEPROP 0 LASTPIN (-5800 4700) $PN 33
J 0
(-5790 4710);
DISPLAY 0.489362 (-5790 4710);
PAINT MONO (-5790 4710);
FORCEPROP 0 LASTPIN (-6650 4100) $PN 31
J 2
(-6660 4110);
DISPLAY 0.489362 (-6660 4110);
PAINT MONO (-6660 4110);
FORCEPROP 0 LASTPIN (-6650 4500) $PN 35
J 2
(-6660 4510);
DISPLAY 0.489362 (-6660 4510);
PAINT MONO (-6660 4510);
FORCEPROP 0 LASTPIN (-5800 4050) $PN 6
J 0
(-5790 4060);
DISPLAY 0.489362 (-5790 4060);
PAINT MONO (-5790 4060);
FORCEPROP 0 LASTPIN (-5800 4000) $PN 41
J 0
(-5790 4010);
DISPLAY 0.489362 (-5790 4010);
PAINT MONO (-5790 4010);
FORCEPROP 0 LASTPIN (-6650 4350) $PN 38
J 2
(-6660 4360);
DISPLAY 0.489362 (-6660 4360);
PAINT MONO (-6660 4360);
FORCEPROP 0 LASTPIN (-6650 4050) $PN 37
J 2
(-6660 4060);
DISPLAY 0.489362 (-6660 4060);
PAINT MONO (-6660 4060);
FORCEPROP 0 LASTPIN (-5800 3850) $PN 5
J 0
(-5790 3860);
DISPLAY 0.489362 (-5790 3860);
PAINT MONO (-5790 3860);
FORCEPROP 0 LASTPIN (-5800 3800) $PN 7_9-20_24
J 0
(-5790 3810);
DISPLAY 0.489362 (-5790 3810);
PAINT MONO (-5790 3810);
FORCEPROP 0 LASTPIN (-5800 3750) $PN 40
J 0
(-5790 3760);
DISPLAY 0.489362 (-5790 3760);
PAINT MONO (-5790 3760);
FORCEPROP 0 LASTPIN (-5800 4450) $PN 32
J 0
(-5790 4460);
DISPLAY 0.489362 (-5790 4460);
PAINT MONO (-5790 4460);
FORCEPROP 0 LASTPIN (-6650 5000) $PN 4
J 2
(-6660 5010);
DISPLAY 0.489362 (-6660 5010);
PAINT MONO (-6660 5010);
FORCEPROP 0 LASTPIN (-6650 3750) $PN 34
J 2
(-6660 3760);
DISPLAY 0.489362 (-6660 3760);
PAINT MONO (-6660 3760);
FORCEPROP 0 LASTPIN (-6650 4250) $PN 39
J 2
(-6660 4260);
DISPLAY 0.489362 (-6660 4260);
PAINT MONO (-6660 4260);
FORCEPROP 0 LASTPIN (-5800 4350) $PN 10_19
J 0
(-5790 4360);
DISPLAY 0.489362 (-5790 4360);
PAINT MONO (-5790 4360);
FORCEPROP 0 LASTPIN (-6650 3850) $PN 36
J 2
(-6660 3860);
DISPLAY 0.489362 (-6660 3860);
PAINT MONO (-6660 3860);
FORCEPROP 0 LASTPIN (-6650 4700) $PN 3
J 2
(-6660 4710);
DISPLAY 0.489362 (-6660 4710);
PAINT MONO (-6660 4710);
FORCEPROP 0 LASTPIN (-5800 5000) $PN 25_29
J 0
(-5790 5010);
DISPLAY 0.489362 (-5790 5010);
PAINT MONO (-5790 5010);
FORCEPROP 0 LASTPIN (-5800 4950) $PN 30
J 0
(-5790 4960);
DISPLAY 0.489362 (-5790 4960);
PAINT MONO (-5790 4960);
FORCEPROP 0 LASTPIN (-5800 4100) $PN 1
J 0
(-5790 4110);
DISPLAY 0.489362 (-5790 4110);
PAINT MONO (-5790 4110);
FORCEPROP 2 LAST VALUE ISL99390FRZ-TR5935
J 0
(-6500 5275);
DISPLAY 0.489362 (-6500 5275);
PAINT SKYBLUE (-6500 5275);
FORCEPROP 2 LAST PART_TYPE SMLF
J 0
(-6500 5325);
DISPLAY 1.021277 (-6500 5325);
FORCEPROP 1 LAST MATERIAL IC
J 0
(-6500 5075);
DISPLAY 0.489362 (-6500 5075);
PAINT SKYBLUE (-6500 5075);
FORCEPROP 1 LAST NEEDS_NO_SIZE TRUE
J 0
(-6200 4350);
DISPLAY 0.723404 (-6200 4350);
PAINT GREEN (-6200 4350);
DISPLAY INVISIBLE (-6200 4350);
FORCEPROP 2 LAST CDS_LIB pure_quanta
J 0
(-6200 4350);
DISPLAY INVISIBLE (-6200 4350);
FORCEPROP 1 LAST CDS_LMAN_SYM_OUTLINE -300,700,250,-650
J 0
(-6200 4350);
DISPLAY 0.468085 (-6200 4350);
PAINT GREEN (-6200 4350);
DISPLAY INVISIBLE (-6200 4350);
FORCEPROP 1 LAST PATH I26
J 0
(-6200 4350);
DISPLAY 0.723404 (-6200 4350);
PAINT GREEN (-6200 4350);
DISPLAY INVISIBLE (-6200 4350);
FORCEPROP 1 LAST PART_NUMBER AL099390004
J 0
(-6500 5150);
DISPLAY 0.489362 (-6500 5150);
PAINT SKYBLUE (-6500 5150);
DISPLAY INVISIBLE (-6500 5150);
FORCEADD UNIVERSAL_GND..1
(-5625 875);
FORCEPROP 3 LASTPIN (-5625 925) SIG_NAME GND\g
J 0
(-5615 935);
DISPLAY 0.659574 (-5615 935);
PAINT MONO (-5615 935);
DISPLAY INVISIBLE (-5615 935);
FORCEPROP 2 LAST CDS_LIB pure_quanta_power
J 0
(-5625 875);
DISPLAY INVISIBLE (-5625 875);
FORCEPROP 1 LAST HDL_POWER GND
J 1
(-5600 800);
DISPLAY 0.872340 (-5600 800);
PAINT GREEN (-5600 800);
DISPLAY INVISIBLE (-5600 800);
FORCEPROP 1 LAST PATH I27
J 0
(-5550 875);
DISPLAY 0.872340 (-5550 875);
PAINT AQUA (-5550 875);
DISPLAY INVISIBLE (-5550 875);
FORCEADD Q_RES..2
(-4650 975);
FORCEPROP 1 LAST LOCATION PR496
J 0
(-4605 1100);
DISPLAY 0.489362 (-4605 1100);
PAINT SKYBLUE (-4605 1100);
FORCEPROP 0 LAST $SEC 1
J 0
(-4600 1150);
DISPLAY 0.680851 (-4600 1150);
PAINT MONO (-4600 1150);
DISPLAY INVISIBLE (-4600 1150);
FORCEPROP 0 LAST CDS_SEC 1
J 0
(-4600 1150);
DISPLAY 1.021277 (-4600 1150);
DISPLAY INVISIBLE (-4600 1150);
FORCEPROP 1 LASTPIN (-4650 1075) $PN 1
J 0
(-4645 1037);
DISPLAY 0.489362 (-4645 1037);
PAINT MONO (-4645 1037);
FORCEPROP 1 LASTPIN (-4650 875) $PN 2
J 0
(-4645 885);
DISPLAY 0.489362 (-4645 885);
PAINT MONO (-4645 885);
FORCEPROP 1 LAST PACK_TYPE 0402LF
J 0
(-4610 800);
DISPLAY 0.489362 (-4610 800);
PAINT SKYBLUE (-4610 800);
FORCEPROP 1 LAST VALUE 1.5
J 0
(-4605 1050);
DISPLAY 0.489362 (-4605 1050);
PAINT SKYBLUE (-4605 1050);
FORCEPROP 1 LAST TOLERANCE 1%
J 0
(-4605 1000);
DISPLAY 0.489362 (-4605 1000);
PAINT SKYBLUE (-4605 1000);
FORCEPROP 1 LAST MATERIAL EMPTY
J 0
(-4610 900);
DISPLAY 0.489362 (-4610 900);
PAINT RED (-4610 900);
FORCEPROP 1 LAST WATTAGE 1/8W
J 0
(-4610 950);
DISPLAY 0.489362 (-4610 950);
PAINT SKYBLUE (-4610 950);
FORCEPROP 2 LAST CDS_LIB pure_quanta
J 0
(-4650 975);
DISPLAY INVISIBLE (-4650 975);
FORCEPROP 1 LAST PATH I28
J 0
(-4600 1150);
DISPLAY 0.978723 (-4600 1150);
PAINT WHITE (-4600 1150);
DISPLAY INVISIBLE (-4600 1150);
FORCEPROP 1 LAST PART_NUMBER CS-1504FB00
J 0
(-4610 850);
DISPLAY 0.489362 (-4610 850);
PAINT SKYBLUE (-4610 850);
DISPLAY INVISIBLE (-4610 850);
FORCEADD UNIVERSAL_GND..1
(-4650 750);
FORCEPROP 3 LASTPIN (-4650 800) SIG_NAME GND\g
J 0
(-4640 810);
DISPLAY 0.659574 (-4640 810);
PAINT MONO (-4640 810);
DISPLAY INVISIBLE (-4640 810);
FORCEPROP 2 LAST CDS_LIB pure_quanta_power
J 0
(-4650 750);
DISPLAY INVISIBLE (-4650 750);
FORCEPROP 1 LAST HDL_POWER GND
J 1
(-4625 675);
DISPLAY 0.872340 (-4625 675);
PAINT GREEN (-4625 675);
DISPLAY INVISIBLE (-4625 675);
FORCEPROP 1 LAST PATH I29
J 0
(-4575 750);
DISPLAY 0.872340 (-4575 750);
PAINT AQUA (-4575 750);
DISPLAY INVISIBLE (-4575 750);
FORCEADD Q_RES..1
R 1
(-8625 5625);
FORCEPROP 1 LAST LOCATION PR445
J 0
(-8600 5775);
DISPLAY 0.489362 (-8600 5775);
PAINT SKYBLUE (-8600 5775);
FORCEPROP 0 LAST $SEC 1
R 1
J 0
(-8600 5800);
DISPLAY 0.680851 (-8600 5800);
PAINT MONO (-8600 5800);
DISPLAY INVISIBLE (-8600 5800);
FORCEPROP 0 LAST CDS_SEC 1
R 1
J 0
(-8600 5800);
DISPLAY 1.021277 (-8600 5800);
DISPLAY INVISIBLE (-8600 5800);
FORCEPROP 1 LASTPIN (-8625 5525) $PN 1
R 1
J 0
(-8637 5537);
DISPLAY 0.787234 (-8637 5537);
PAINT MONO (-8637 5537);
DISPLAY INVISIBLE (-8637 5537);
FORCEPROP 1 LASTPIN (-8625 5725) $PN 2
R 1
J 0
(-8637 5687);
DISPLAY 0.787234 (-8637 5687);
PAINT MONO (-8637 5687);
DISPLAY INVISIBLE (-8637 5687);
FORCEPROP 1 LAST WATTAGE 1/16W
J 0
(-8600 5625);
DISPLAY 0.489362 (-8600 5625);
PAINT SKYBLUE (-8600 5625);
FORCEPROP 1 LAST MATERIAL CHIP
J 0
(-8600 5575);
DISPLAY 0.489362 (-8600 5575);
PAINT SKYBLUE (-8600 5575);
FORCEPROP 1 LAST TOLERANCE 5%
J 0
(-8600 5675);
DISPLAY 0.489362 (-8600 5675);
PAINT SKYBLUE (-8600 5675);
FORCEPROP 1 LAST VALUE 0
J 2
(-8575 5725);
DISPLAY 0.489362 (-8575 5725);
PAINT SKYBLUE (-8575 5725);
FORCEPROP 1 LAST PACK_TYPE 0402LF
J 0
(-8600 5475);
DISPLAY 0.489362 (-8600 5475);
PAINT SKYBLUE (-8600 5475);
FORCEPROP 2 LAST CDS_LIB pure_quanta
R 1
J 0
(-8625 5625);
DISPLAY INVISIBLE (-8625 5625);
FORCEPROP 1 LAST PATH I3
R 1
J 0
(-8775 5575);
DISPLAY 0.978723 (-8775 5575);
PAINT WHITE (-8775 5575);
DISPLAY INVISIBLE (-8775 5575);
FORCEPROP 1 LAST PART_NUMBER CS00002JB13
J 0
(-8600 5525);
DISPLAY 0.489362 (-8600 5525);
PAINT SKYBLUE (-8600 5525);
DISPLAY INVISIBLE (-8600 5525);
FORCEADD Q_RES..1
(-4250 675);
FORCEPROP 1 LAST LOCATION PR325
J 0
(-4300 725);
DISPLAY 0.489362 (-4300 725);
PAINT SKYBLUE (-4300 725);
FORCEPROP 0 LAST $SEC 1
J 0
(-4250 750);
DISPLAY 0.680851 (-4250 750);
PAINT MONO (-4250 750);
DISPLAY INVISIBLE (-4250 750);
FORCEPROP 0 LAST CDS_SEC 1
J 0
(-4250 750);
DISPLAY 1.021277 (-4250 750);
DISPLAY INVISIBLE (-4250 750);
FORCEPROP 1 LASTPIN (-4350 675) $PN 1
J 0
(-4338 687);
DISPLAY 0.489362 (-4338 687);
PAINT MONO (-4338 687);
FORCEPROP 1 LASTPIN (-4150 675) $PN 2
J 0
(-4188 687);
DISPLAY 0.489362 (-4188 687);
PAINT MONO (-4188 687);
FORCEPROP 1 LAST WATTAGE 1/16W
J 0
(-4150 625);
DISPLAY 0.489362 (-4150 625);
PAINT SKYBLUE (-4150 625);
FORCEPROP 1 LAST MATERIAL CHIP
J 0
(-4500 575);
DISPLAY 0.489362 (-4500 575);
PAINT SKYBLUE (-4500 575);
FORCEPROP 1 LAST TOLERANCE 5%
J 0
(-4125 700);
DISPLAY 0.489362 (-4125 700);
PAINT SKYBLUE (-4125 700);
FORCEPROP 1 LAST VALUE 0
J 2
(-4375 700);
DISPLAY 0.489362 (-4375 700);
PAINT SKYBLUE (-4375 700);
FORCEPROP 1 LAST PACK_TYPE 0402LF
J 0
(-4150 575);
DISPLAY 0.489362 (-4150 575);
PAINT SKYBLUE (-4150 575);
FORCEPROP 2 LAST CDS_LIB pure_quanta
J 0
(-4250 675);
DISPLAY INVISIBLE (-4250 675);
FORCEPROP 1 LAST PATH I30
J 0
(-4300 825);
DISPLAY 0.978723 (-4300 825);
PAINT WHITE (-4300 825);
DISPLAY INVISIBLE (-4300 825);
FORCEPROP 1 LAST PART_NUMBER CS00002JB13
J 0
(-4575 625);
DISPLAY 0.489362 (-4575 625);
PAINT SKYBLUE (-4575 625);
DISPLAY INVISIBLE (-4575 625);
FORCEADD Q_CAP..1
(-4650 1425);
FORCEPROP 1 LAST LOCATION PC179
J 0
(-4600 1525);
DISPLAY 0.489362 (-4600 1525);
PAINT SKYBLUE (-4600 1525);
FORCEPROP 0 LAST $SEC 1
J 0
(-4600 1575);
DISPLAY 0.680851 (-4600 1575);
PAINT MONO (-4600 1575);
DISPLAY INVISIBLE (-4600 1575);
FORCEPROP 0 LAST CDS_SEC 1
J 0
(-4600 1575);
DISPLAY 1.021277 (-4600 1575);
DISPLAY INVISIBLE (-4600 1575);
FORCEPROP 1 LASTPIN (-4650 1525) $PN 1
J 0
(-4640 1505);
DISPLAY 0.489362 (-4640 1505);
PAINT MONO (-4640 1505);
FORCEPROP 1 LASTPIN (-4650 1325) $PN 2
J 0
(-4640 1305);
DISPLAY 0.489362 (-4640 1305);
PAINT MONO (-4640 1305);
FORCEPROP 1 LAST TOLERANCE 10%
J 0
(-4600 1375);
DISPLAY 0.489362 (-4600 1375);
PAINT SKYBLUE (-4600 1375);
FORCEPROP 1 LAST VOLTAGE 50V
J 0
(-4600 1425);
DISPLAY 0.489362 (-4600 1425);
PAINT SKYBLUE (-4600 1425);
FORCEPROP 1 LAST MATERIAL EMPTY
J 0
(-4600 1325);
DISPLAY 0.489362 (-4600 1325);
PAINT RED (-4600 1325);
FORCEPROP 1 LAST PACK_TYPE C0402
J 0
(-4600 1225);
DISPLAY 0.489362 (-4600 1225);
PAINT SKYBLUE (-4600 1225);
FORCEPROP 1 LAST VALUE 560PF
J 0
(-4600 1475);
DISPLAY 0.489362 (-4600 1475);
PAINT SKYBLUE (-4600 1475);
FORCEPROP 2 LAST CDS_LIB pure_quanta
J 0
(-4650 1425);
DISPLAY INVISIBLE (-4650 1425);
FORCEPROP 1 LAST PATH I31
J 0
(-4600 1575);
DISPLAY 0.978723 (-4600 1575);
PAINT WHITE (-4600 1575);
DISPLAY INVISIBLE (-4600 1575);
FORCEPROP 1 LAST PART_NUMBER CH1566K1B09
J 0
(-4600 1275);
DISPLAY 0.489362 (-4600 1275);
PAINT SKYBLUE (-4600 1275);
DISPLAY INVISIBLE (-4600 1275);
FORCEADD Q_RES..1
(-4725 1950);
FORCEPROP 1 LAST LOCATION PR323
J 0
(-4750 2000);
DISPLAY 0.489362 (-4750 2000);
PAINT SKYBLUE (-4750 2000);
FORCEPROP 0 LAST $SEC 1
J 0
(-4700 2025);
DISPLAY 0.680851 (-4700 2025);
PAINT MONO (-4700 2025);
DISPLAY INVISIBLE (-4700 2025);
FORCEPROP 0 LAST CDS_SEC 1
J 0
(-4700 2025);
DISPLAY 1.021277 (-4700 2025);
DISPLAY INVISIBLE (-4700 2025);
FORCEPROP 1 LASTPIN (-4825 1950) $PN 1
J 0
(-4813 1962);
DISPLAY 0.489362 (-4813 1962);
PAINT MONO (-4813 1962);
FORCEPROP 1 LASTPIN (-4625 1950) $PN 2
J 0
(-4663 1962);
DISPLAY 0.489362 (-4663 1962);
PAINT MONO (-4663 1962);
FORCEPROP 1 LAST MATERIAL CHIP
J 0
(-4975 1850);
DISPLAY 0.489362 (-4975 1850);
PAINT SKYBLUE (-4975 1850);
FORCEPROP 1 LAST TOLERANCE 1%
J 0
(-4600 1975);
DISPLAY 0.489362 (-4600 1975);
PAINT SKYBLUE (-4600 1975);
FORCEPROP 1 LAST PACK_TYPE 0402LF
J 0
(-4625 1850);
DISPLAY 0.489362 (-4625 1850);
PAINT SKYBLUE (-4625 1850);
FORCEPROP 1 LAST WATTAGE 1/16W
J 0
(-4625 1900);
DISPLAY 0.489362 (-4625 1900);
PAINT SKYBLUE (-4625 1900);
FORCEPROP 1 LAST VALUE 5.6
J 2
(-4850 1975);
DISPLAY 0.489362 (-4850 1975);
PAINT SKYBLUE (-4850 1975);
FORCEPROP 2 LAST CDS_LIB pure_quanta
J 0
(-4725 1950);
DISPLAY INVISIBLE (-4725 1950);
FORCEPROP 1 LAST PATH I32
J 0
(-4775 2100);
DISPLAY 0.978723 (-4775 2100);
PAINT WHITE (-4775 2100);
DISPLAY INVISIBLE (-4775 2100);
FORCEPROP 1 LAST PART_NUMBER CS-5602FB01
J 0
(-4975 1900);
DISPLAY 0.489362 (-4975 1900);
PAINT SKYBLUE (-4975 1900);
DISPLAY INVISIBLE (-4975 1900);
FORCEADD Q_CAP..1
(-5550 2475);
FORCEPROP 1 LAST LOCATION PC482_2
J 0
(-5500 2575);
DISPLAY 0.489362 (-5500 2575);
PAINT SKYBLUE (-5500 2575);
FORCEPROP 0 LAST $SEC 1
J 0
(-5500 2625);
DISPLAY 0.680851 (-5500 2625);
PAINT MONO (-5500 2625);
DISPLAY INVISIBLE (-5500 2625);
FORCEPROP 0 LAST CDS_SEC 1
J 0
(-5500 2625);
DISPLAY 1.021277 (-5500 2625);
DISPLAY INVISIBLE (-5500 2625);
FORCEPROP 1 LASTPIN (-5550 2575) $PN 1
J 0
(-5540 2555);
DISPLAY 0.489362 (-5540 2555);
PAINT MONO (-5540 2555);
FORCEPROP 1 LASTPIN (-5550 2375) $PN 2
J 0
(-5540 2355);
DISPLAY 0.489362 (-5540 2355);
PAINT MONO (-5540 2355);
FORCEPROP 1 LAST VALUE 0.1UF
J 0
(-5500 2525);
DISPLAY 0.489362 (-5500 2525);
PAINT SKYBLUE (-5500 2525);
FORCEPROP 1 LAST VOLTAGE 25V
J 0
(-5500 2475);
DISPLAY 0.489362 (-5500 2475);
PAINT SKYBLUE (-5500 2475);
FORCEPROP 1 LAST PACK_TYPE 0402
J 0
(-5500 2275);
DISPLAY 0.489362 (-5500 2275);
PAINT SKYBLUE (-5500 2275);
FORCEPROP 1 LAST MATERIAL X7R
J 0
(-5500 2375);
DISPLAY 0.489362 (-5500 2375);
PAINT SKYBLUE (-5500 2375);
FORCEPROP 1 LAST TOLERANCE 10%
J 0
(-5500 2425);
DISPLAY 0.489362 (-5500 2425);
PAINT SKYBLUE (-5500 2425);
FORCEPROP 2 LAST CDS_LIB pure_quanta
J 0
(-5550 2475);
DISPLAY INVISIBLE (-5550 2475);
FORCEPROP 1 LAST PATH I33
J 0
(-5500 2625);
DISPLAY 0.978723 (-5500 2625);
PAINT WHITE (-5500 2625);
DISPLAY INVISIBLE (-5500 2625);
FORCEPROP 1 LAST PART_NUMBER CH4104K1B00
J 0
(-5500 2325);
DISPLAY 0.489362 (-5500 2325);
PAINT SKYBLUE (-5500 2325);
DISPLAY INVISIBLE (-5500 2325);
FORCEADD Q_CAP..1
(-5225 2475);
FORCEPROP 1 LAST LOCATION PC480_2
J 0
(-5175 2575);
DISPLAY 0.489362 (-5175 2575);
PAINT SKYBLUE (-5175 2575);
FORCEPROP 0 LAST $SEC 1
J 0
(-5175 2600);
DISPLAY 0.680851 (-5175 2600);
PAINT MONO (-5175 2600);
DISPLAY INVISIBLE (-5175 2600);
FORCEPROP 0 LAST CDS_SEC 1
J 0
(-5175 2600);
DISPLAY 1.021277 (-5175 2600);
DISPLAY INVISIBLE (-5175 2600);
FORCEPROP 1 LASTPIN (-5225 2575) $PN 1
J 0
(-5215 2555);
DISPLAY 0.489362 (-5215 2555);
PAINT MONO (-5215 2555);
FORCEPROP 1 LASTPIN (-5225 2375) $PN 2
J 0
(-5215 2355);
DISPLAY 0.489362 (-5215 2355);
PAINT MONO (-5215 2355);
FORCEPROP 1 LAST TOLERANCE 10%
J 0
(-5175 2425);
DISPLAY 0.489362 (-5175 2425);
PAINT SKYBLUE (-5175 2425);
FORCEPROP 1 LAST MATERIAL X6S
J 0
(-5175 2375);
DISPLAY 0.489362 (-5175 2375);
PAINT SKYBLUE (-5175 2375);
FORCEPROP 1 LAST VALUE 1UF
J 0
(-5175 2525);
DISPLAY 0.489362 (-5175 2525);
PAINT SKYBLUE (-5175 2525);
FORCEPROP 1 LAST VOLTAGE 25V
J 0
(-5175 2475);
DISPLAY 0.489362 (-5175 2475);
PAINT SKYBLUE (-5175 2475);
FORCEPROP 1 LAST PACK_TYPE C0402
J 0
(-5175 2275);
DISPLAY 0.489362 (-5175 2275);
PAINT SKYBLUE (-5175 2275);
FORCEPROP 2 LAST CDS_LIB pure_quanta
J 0
(-5225 2475);
DISPLAY INVISIBLE (-5225 2475);
FORCEPROP 1 LAST PATH I34
J 0
(-5175 2625);
DISPLAY 0.978723 (-5175 2625);
PAINT WHITE (-5175 2625);
DISPLAY INVISIBLE (-5175 2625);
FORCEPROP 1 LAST PART_NUMBER CH5104KEB02
J 0
(-5175 2325);
DISPLAY 0.489362 (-5175 2325);
PAINT SKYBLUE (-5175 2325);
DISPLAY INVISIBLE (-5175 2325);
FORCEADD UNIVERSAL_GND..1
(-5625 3625);
FORCEPROP 3 LASTPIN (-5625 3675) SIG_NAME GND\g
J 0
(-5615 3685);
DISPLAY 0.659574 (-5615 3685);
PAINT MONO (-5615 3685);
DISPLAY INVISIBLE (-5615 3685);
FORCEPROP 2 LAST CDS_LIB pure_quanta_power
J 0
(-5625 3625);
DISPLAY INVISIBLE (-5625 3625);
FORCEPROP 1 LAST HDL_POWER GND
J 1
(-5600 3550);
DISPLAY 0.872340 (-5600 3550);
PAINT GREEN (-5600 3550);
DISPLAY INVISIBLE (-5600 3550);
FORCEPROP 1 LAST PATH I35
J 0
(-5550 3625);
DISPLAY 0.872340 (-5550 3625);
PAINT AQUA (-5550 3625);
DISPLAY INVISIBLE (-5550 3625);
FORCEADD Q_CAP..1
(-4900 2475);
FORCEPROP 1 LAST LOCATION PC484_2
J 0
(-4850 2575);
DISPLAY 0.489362 (-4850 2575);
PAINT SKYBLUE (-4850 2575);
FORCEPROP 0 LAST $SEC 1
J 0
(-4850 2600);
DISPLAY 0.680851 (-4850 2600);
PAINT MONO (-4850 2600);
DISPLAY INVISIBLE (-4850 2600);
FORCEPROP 0 LAST CDS_SEC 1
J 0
(-4850 2600);
DISPLAY 1.021277 (-4850 2600);
DISPLAY INVISIBLE (-4850 2600);
FORCEPROP 1 LASTPIN (-4900 2575) $PN 1
J 0
(-4890 2555);
DISPLAY 0.489362 (-4890 2555);
PAINT MONO (-4890 2555);
FORCEPROP 1 LASTPIN (-4900 2375) $PN 2
J 0
(-4890 2355);
DISPLAY 0.489362 (-4890 2355);
PAINT MONO (-4890 2355);
FORCEPROP 1 LAST PACK_TYPE C0805
J 0
(-4850 2275);
DISPLAY 0.489362 (-4850 2275);
PAINT SKYBLUE (-4850 2275);
FORCEPROP 1 LAST VOLTAGE 16V
J 0
(-4850 2475);
DISPLAY 0.489362 (-4850 2475);
PAINT SKYBLUE (-4850 2475);
FORCEPROP 1 LAST TOLERANCE 20%
J 0
(-4850 2425);
DISPLAY 0.489362 (-4850 2425);
PAINT SKYBLUE (-4850 2425);
FORCEPROP 1 LAST VALUE 22UF
J 0
(-4850 2525);
DISPLAY 0.489362 (-4850 2525);
PAINT SKYBLUE (-4850 2525);
FORCEPROP 1 LAST MATERIAL X6S
J 0
(-4850 2375);
DISPLAY 0.489362 (-4850 2375);
PAINT SKYBLUE (-4850 2375);
FORCEPROP 2 LAST CDS_LIB pure_quanta
J 0
(-4900 2475);
DISPLAY INVISIBLE (-4900 2475);
FORCEPROP 1 LAST PATH I36
J 0
(-4850 2625);
DISPLAY 0.978723 (-4850 2625);
PAINT WHITE (-4850 2625);
DISPLAY INVISIBLE (-4850 2625);
FORCEPROP 1 LAST PART_NUMBER CH6223MEA01
J 0
(-4850 2325);
DISPLAY 0.489362 (-4850 2325);
PAINT SKYBLUE (-4850 2325);
DISPLAY INVISIBLE (-4850 2325);
FORCEADD Q_CAP..1
(-4575 2475);
FORCEPROP 1 LAST LOCATION PC486_2
J 0
(-4525 2575);
DISPLAY 0.489362 (-4525 2575);
PAINT SKYBLUE (-4525 2575);
FORCEPROP 0 LAST $SEC 1
J 0
(-4525 2600);
DISPLAY 0.680851 (-4525 2600);
PAINT MONO (-4525 2600);
DISPLAY INVISIBLE (-4525 2600);
FORCEPROP 0 LAST CDS_SEC 1
J 0
(-4525 2600);
DISPLAY 1.021277 (-4525 2600);
DISPLAY INVISIBLE (-4525 2600);
FORCEPROP 1 LASTPIN (-4575 2575) $PN 1
J 0
(-4565 2555);
DISPLAY 0.489362 (-4565 2555);
PAINT MONO (-4565 2555);
FORCEPROP 1 LASTPIN (-4575 2375) $PN 2
J 0
(-4565 2355);
DISPLAY 0.489362 (-4565 2355);
PAINT MONO (-4565 2355);
FORCEPROP 1 LAST PACK_TYPE C0805
J 0
(-4525 2275);
DISPLAY 0.489362 (-4525 2275);
PAINT SKYBLUE (-4525 2275);
FORCEPROP 1 LAST VALUE 22UF
J 0
(-4525 2525);
DISPLAY 0.489362 (-4525 2525);
PAINT SKYBLUE (-4525 2525);
FORCEPROP 1 LAST TOLERANCE 20%
J 0
(-4525 2425);
DISPLAY 0.489362 (-4525 2425);
PAINT SKYBLUE (-4525 2425);
FORCEPROP 1 LAST VOLTAGE 16V
J 0
(-4525 2475);
DISPLAY 0.489362 (-4525 2475);
PAINT SKYBLUE (-4525 2475);
FORCEPROP 1 LAST MATERIAL X6S
J 0
(-4525 2375);
DISPLAY 0.489362 (-4525 2375);
PAINT SKYBLUE (-4525 2375);
FORCEPROP 2 LAST CDS_LIB pure_quanta
J 0
(-4575 2475);
DISPLAY INVISIBLE (-4575 2475);
FORCEPROP 1 LAST PATH I37
J 0
(-4525 2625);
DISPLAY 0.978723 (-4525 2625);
PAINT WHITE (-4525 2625);
DISPLAY INVISIBLE (-4525 2625);
FORCEPROP 1 LAST PART_NUMBER CH6223MEA01
J 0
(-4525 2325);
DISPLAY 0.489362 (-4525 2325);
PAINT SKYBLUE (-4525 2325);
DISPLAY INVISIBLE (-4525 2325);
FORCEADD UNIVERSAL_GND..1
(-4275 2125);
FORCEPROP 3 LASTPIN (-4275 2175) SIG_NAME GND\g
J 0
(-4265 2185);
DISPLAY 0.659574 (-4265 2185);
PAINT MONO (-4265 2185);
DISPLAY INVISIBLE (-4265 2185);
FORCEPROP 2 LAST CDS_LIB pure_quanta_power
J 0
(-4275 2125);
DISPLAY INVISIBLE (-4275 2125);
FORCEPROP 1 LAST HDL_POWER GND
J 1
(-4250 2050);
DISPLAY 0.872340 (-4250 2050);
PAINT GREEN (-4250 2050);
DISPLAY INVISIBLE (-4250 2050);
FORCEPROP 1 LAST PATH I38
J 0
(-4200 2125);
DISPLAY 0.872340 (-4200 2125);
PAINT AQUA (-4200 2125);
DISPLAY INVISIBLE (-4200 2125);
FORCEADD Q_CAP..1
(-4275 2475);
FORCEPROP 1 LAST LOCATION PC488_2
J 0
(-4225 2575);
DISPLAY 0.489362 (-4225 2575);
PAINT SKYBLUE (-4225 2575);
FORCEPROP 0 LAST $SEC 1
J 0
(-4225 2600);
DISPLAY 0.680851 (-4225 2600);
PAINT MONO (-4225 2600);
DISPLAY INVISIBLE (-4225 2600);
FORCEPROP 0 LAST CDS_SEC 1
J 0
(-4225 2600);
DISPLAY 1.021277 (-4225 2600);
DISPLAY INVISIBLE (-4225 2600);
FORCEPROP 1 LASTPIN (-4275 2575) $PN 1
J 0
(-4265 2555);
DISPLAY 0.489362 (-4265 2555);
PAINT MONO (-4265 2555);
FORCEPROP 1 LASTPIN (-4275 2375) $PN 2
J 0
(-4265 2355);
DISPLAY 0.489362 (-4265 2355);
PAINT MONO (-4265 2355);
FORCEPROP 1 LAST TOLERANCE 20%
J 0
(-4225 2425);
DISPLAY 0.489362 (-4225 2425);
PAINT SKYBLUE (-4225 2425);
FORCEPROP 1 LAST MATERIAL X6S
J 0
(-4225 2375);
DISPLAY 0.489362 (-4225 2375);
PAINT SKYBLUE (-4225 2375);
FORCEPROP 1 LAST PACK_TYPE C0805
J 0
(-4225 2275);
DISPLAY 0.489362 (-4225 2275);
PAINT SKYBLUE (-4225 2275);
FORCEPROP 1 LAST VOLTAGE 16V
J 0
(-4225 2475);
DISPLAY 0.489362 (-4225 2475);
PAINT SKYBLUE (-4225 2475);
FORCEPROP 1 LAST VALUE 22UF
J 0
(-4225 2525);
DISPLAY 0.489362 (-4225 2525);
PAINT SKYBLUE (-4225 2525);
FORCEPROP 2 LAST CDS_LIB pure_quanta
J 0
(-4275 2475);
DISPLAY INVISIBLE (-4275 2475);
FORCEPROP 1 LAST PATH I39
J 0
(-4225 2625);
DISPLAY 0.978723 (-4225 2625);
PAINT WHITE (-4225 2625);
DISPLAY INVISIBLE (-4225 2625);
FORCEPROP 1 LAST PART_NUMBER CH6223MEA01
J 0
(-4225 2325);
DISPLAY 0.489362 (-4225 2325);
PAINT SKYBLUE (-4225 2325);
DISPLAY INVISIBLE (-4225 2325);
FORCEADD Q_RES..1
R 1
(-8275 5625);
FORCEPROP 1 LAST LOCATION PR446
J 0
(-8225 5775);
DISPLAY 0.489362 (-8225 5775);
PAINT SKYBLUE (-8225 5775);
FORCEPROP 0 LAST $SEC 1
R 1
J 0
(-8225 5800);
DISPLAY 0.680851 (-8225 5800);
PAINT MONO (-8225 5800);
DISPLAY INVISIBLE (-8225 5800);
FORCEPROP 0 LAST CDS_SEC 1
R 1
J 0
(-8225 5800);
DISPLAY 1.021277 (-8225 5800);
DISPLAY INVISIBLE (-8225 5800);
FORCEPROP 1 LASTPIN (-8275 5525) $PN 1
R 1
J 0
(-8287 5537);
DISPLAY 0.787234 (-8287 5537);
PAINT MONO (-8287 5537);
DISPLAY INVISIBLE (-8287 5537);
FORCEPROP 1 LASTPIN (-8275 5725) $PN 2
R 1
J 0
(-8287 5687);
DISPLAY 0.787234 (-8287 5687);
PAINT MONO (-8287 5687);
DISPLAY INVISIBLE (-8287 5687);
FORCEPROP 1 LAST MATERIAL EMPTY
J 0
(-8225 5575);
DISPLAY 0.489362 (-8225 5575);
PAINT RED (-8225 5575);
FORCEPROP 1 LAST WATTAGE 1/16W
J 0
(-8225 5625);
DISPLAY 0.489362 (-8225 5625);
PAINT SKYBLUE (-8225 5625);
FORCEPROP 1 LAST TOLERANCE 5%
J 0
(-8225 5675);
DISPLAY 0.489362 (-8225 5675);
PAINT SKYBLUE (-8225 5675);
FORCEPROP 1 LAST VALUE 0
J 2
(-8200 5725);
DISPLAY 0.489362 (-8200 5725);
PAINT SKYBLUE (-8200 5725);
FORCEPROP 1 LAST PACK_TYPE 0402LF
J 0
(-8225 5475);
DISPLAY 0.489362 (-8225 5475);
PAINT SKYBLUE (-8225 5475);
FORCEPROP 2 LAST CDS_LIB pure_quanta
R 1
J 0
(-8275 5625);
DISPLAY INVISIBLE (-8275 5625);
FORCEPROP 1 LAST PATH I4
R 1
J 0
(-8425 5575);
DISPLAY 0.978723 (-8425 5575);
PAINT WHITE (-8425 5575);
DISPLAY INVISIBLE (-8425 5575);
FORCEPROP 1 LAST PART_NUMBER CS00002JB13
J 0
(-8225 5525);
DISPLAY 0.489362 (-8225 5525);
PAINT SKYBLUE (-8225 5525);
DISPLAY INVISIBLE (-8225 5525);
FORCEADD VCC_CORE..1
(-4275 2775);
FORCEPROP 3 LASTPIN (-4275 2725) SIG_NAME SW_P12V_AUX_PVDDCR_CPU0_P0_FLT\g
J 0
(-4265 2735);
DISPLAY 0.659574 (-4265 2735);
PAINT MONO (-4265 2735);
DISPLAY INVISIBLE (-4265 2735);
FORCEPROP 1 LAST HDL_POWER SW_P12V_AUX_PVDDCR_CPU0_P0_FLT
J 1
(-4275 2825);
DISPLAY 0.489362 (-4275 2825);
PAINT GREEN (-4275 2825);
FORCEPROP 2 LAST CDS_LIB pure_quanta_power
J 0
(-4275 2775);
DISPLAY INVISIBLE (-4275 2775);
FORCEPROP 1 LAST PATH I40
J 0
(-4225 2800);
DISPLAY 0.872340 (-4225 2800);
PAINT AQUA (-4225 2800);
DISPLAY INVISIBLE (-4225 2800);
FORCEADD UNIVERSAL_GND..1
(-4825 3500);
FORCEPROP 3 LASTPIN (-4825 3550) SIG_NAME GND\g
J 0
(-4815 3560);
DISPLAY 0.659574 (-4815 3560);
PAINT MONO (-4815 3560);
DISPLAY INVISIBLE (-4815 3560);
FORCEPROP 2 LAST CDS_LIB pure_quanta_power
J 0
(-4825 3500);
DISPLAY INVISIBLE (-4825 3500);
FORCEPROP 1 LAST HDL_POWER GND
J 1
(-4800 3425);
DISPLAY 0.872340 (-4800 3425);
PAINT GREEN (-4800 3425);
DISPLAY INVISIBLE (-4800 3425);
FORCEPROP 1 LAST PATH I41
J 0
(-4750 3500);
DISPLAY 0.872340 (-4750 3500);
PAINT AQUA (-4750 3500);
DISPLAY INVISIBLE (-4750 3500);
FORCEADD Q_RES..2
(-4825 3725);
FORCEPROP 1 LAST LOCATION PR495
J 0
(-4780 3850);
DISPLAY 0.489362 (-4780 3850);
PAINT SKYBLUE (-4780 3850);
FORCEPROP 0 LAST $SEC 1
J 0
(-4775 3875);
DISPLAY 0.680851 (-4775 3875);
PAINT MONO (-4775 3875);
DISPLAY INVISIBLE (-4775 3875);
FORCEPROP 0 LAST CDS_SEC 1
J 0
(-4775 3875);
DISPLAY 1.021277 (-4775 3875);
DISPLAY INVISIBLE (-4775 3875);
FORCEPROP 1 LASTPIN (-4825 3825) $PN 1
J 0
(-4820 3787);
DISPLAY 0.489362 (-4820 3787);
PAINT MONO (-4820 3787);
FORCEPROP 1 LASTPIN (-4825 3625) $PN 2
J 0
(-4820 3635);
DISPLAY 0.489362 (-4820 3635);
PAINT MONO (-4820 3635);
FORCEPROP 1 LAST TOLERANCE 1%
J 0
(-4780 3750);
DISPLAY 0.489362 (-4780 3750);
PAINT SKYBLUE (-4780 3750);
FORCEPROP 1 LAST VALUE 1.5
J 0
(-4780 3800);
DISPLAY 0.489362 (-4780 3800);
PAINT SKYBLUE (-4780 3800);
FORCEPROP 1 LAST MATERIAL EMPTY
J 0
(-4785 3650);
DISPLAY 0.489362 (-4785 3650);
PAINT RED (-4785 3650);
FORCEPROP 1 LAST WATTAGE 1/8W
J 0
(-4785 3700);
DISPLAY 0.489362 (-4785 3700);
PAINT SKYBLUE (-4785 3700);
FORCEPROP 1 LAST PACK_TYPE 0402LF
J 0
(-4785 3550);
DISPLAY 0.489362 (-4785 3550);
PAINT SKYBLUE (-4785 3550);
FORCEPROP 2 LAST CDS_LIB pure_quanta
J 0
(-4825 3725);
DISPLAY INVISIBLE (-4825 3725);
FORCEPROP 1 LAST PATH I42
J 0
(-4775 3900);
DISPLAY 0.978723 (-4775 3900);
PAINT WHITE (-4775 3900);
DISPLAY INVISIBLE (-4775 3900);
FORCEPROP 1 LAST PART_NUMBER CS-1504FB00
J 0
(-4785 3600);
DISPLAY 0.489362 (-4785 3600);
PAINT SKYBLUE (-4785 3600);
DISPLAY INVISIBLE (-4785 3600);
FORCEADD Q_RES..1
(-4375 3400);
FORCEPROP 1 LAST LOCATION PR324
J 0
(-4425 3450);
DISPLAY 0.489362 (-4425 3450);
PAINT SKYBLUE (-4425 3450);
FORCEPROP 0 LAST $SEC 1
J 0
(-4375 3475);
DISPLAY 0.680851 (-4375 3475);
PAINT MONO (-4375 3475);
DISPLAY INVISIBLE (-4375 3475);
FORCEPROP 0 LAST CDS_SEC 1
J 0
(-4375 3475);
DISPLAY 1.021277 (-4375 3475);
DISPLAY INVISIBLE (-4375 3475);
FORCEPROP 1 LASTPIN (-4475 3400) $PN 1
J 0
(-4463 3412);
DISPLAY 0.489362 (-4463 3412);
PAINT MONO (-4463 3412);
FORCEPROP 1 LASTPIN (-4275 3400) $PN 2
J 0
(-4313 3412);
DISPLAY 0.489362 (-4313 3412);
PAINT MONO (-4313 3412);
FORCEPROP 1 LAST TOLERANCE 5%
J 0
(-4250 3425);
DISPLAY 0.489362 (-4250 3425);
PAINT SKYBLUE (-4250 3425);
FORCEPROP 1 LAST WATTAGE 1/16W
J 0
(-4275 3350);
DISPLAY 0.489362 (-4275 3350);
PAINT SKYBLUE (-4275 3350);
FORCEPROP 1 LAST VALUE 0
J 2
(-4500 3425);
DISPLAY 0.489362 (-4500 3425);
PAINT SKYBLUE (-4500 3425);
FORCEPROP 1 LAST MATERIAL CHIP
J 0
(-4625 3300);
DISPLAY 0.489362 (-4625 3300);
PAINT SKYBLUE (-4625 3300);
FORCEPROP 1 LAST PACK_TYPE 0402LF
J 0
(-4275 3300);
DISPLAY 0.489362 (-4275 3300);
PAINT SKYBLUE (-4275 3300);
FORCEPROP 2 LAST CDS_LIB pure_quanta
J 0
(-4375 3400);
DISPLAY INVISIBLE (-4375 3400);
FORCEPROP 1 LAST PATH I43
J 0
(-4425 3550);
DISPLAY 0.978723 (-4425 3550);
PAINT WHITE (-4425 3550);
DISPLAY INVISIBLE (-4425 3550);
FORCEPROP 1 LAST PART_NUMBER CS00002JB13
J 0
(-4725 3350);
DISPLAY 0.489362 (-4725 3350);
PAINT SKYBLUE (-4725 3350);
DISPLAY INVISIBLE (-4725 3350);
FORCEADD UNIVERSAL_GND..1
(-7975 4500);
FORCEPROP 3 LASTPIN (-7975 4550) SIG_NAME GND\g
J 0
(-7965 4560);
DISPLAY 0.659574 (-7965 4560);
PAINT MONO (-7965 4560);
DISPLAY INVISIBLE (-7965 4560);
FORCEPROP 2 LAST CDS_LIB pure_quanta_power
J 0
(-7975 4500);
DISPLAY INVISIBLE (-7975 4500);
FORCEPROP 1 LAST HDL_POWER GND
J 1
(-7950 4425);
DISPLAY 0.872340 (-7950 4425);
PAINT GREEN (-7950 4425);
DISPLAY INVISIBLE (-7950 4425);
FORCEPROP 1 LAST PATH I44
J 0
(-7900 4500);
DISPLAY 0.872340 (-7900 4500);
PAINT AQUA (-7900 4500);
DISPLAY INVISIBLE (-7900 4500);
FORCEADD Q_CAP..1
(-7975 4700);
FORCEPROP 1 LAST LOCATION PC475
J 0
(-7925 4800);
DISPLAY 0.489362 (-7925 4800);
PAINT SKYBLUE (-7925 4800);
FORCEPROP 0 LAST $SEC 1
J 0
(-7925 4825);
DISPLAY 0.680851 (-7925 4825);
PAINT MONO (-7925 4825);
DISPLAY INVISIBLE (-7925 4825);
FORCEPROP 0 LAST CDS_SEC 1
J 0
(-7925 4825);
DISPLAY 1.021277 (-7925 4825);
DISPLAY INVISIBLE (-7925 4825);
FORCEPROP 1 LASTPIN (-7975 4800) $PN 1
J 0
(-7965 4780);
DISPLAY 0.489362 (-7965 4780);
PAINT MONO (-7965 4780);
FORCEPROP 1 LASTPIN (-7975 4600) $PN 2
J 0
(-7965 4580);
DISPLAY 0.489362 (-7965 4580);
PAINT MONO (-7965 4580);
FORCEPROP 1 LAST VOLTAGE 10V
J 0
(-7925 4700);
DISPLAY 0.489362 (-7925 4700);
PAINT SKYBLUE (-7925 4700);
FORCEPROP 1 LAST VALUE 2.2UF
J 0
(-7925 4750);
DISPLAY 0.489362 (-7925 4750);
PAINT SKYBLUE (-7925 4750);
FORCEPROP 1 LAST TOLERANCE 10%
J 0
(-7925 4650);
DISPLAY 0.489362 (-7925 4650);
PAINT SKYBLUE (-7925 4650);
FORCEPROP 1 LAST MATERIAL X6S
J 0
(-7925 4600);
DISPLAY 0.489362 (-7925 4600);
PAINT SKYBLUE (-7925 4600);
FORCEPROP 1 LAST PACK_TYPE C0402
J 0
(-7925 4500);
DISPLAY 0.489362 (-7925 4500);
PAINT SKYBLUE (-7925 4500);
FORCEPROP 2 LAST CDS_LIB pure_quanta
J 0
(-7975 4700);
DISPLAY INVISIBLE (-7975 4700);
FORCEPROP 1 LAST PATH I45
J 0
(-7925 4850);
DISPLAY 0.978723 (-7925 4850);
PAINT WHITE (-7925 4850);
DISPLAY INVISIBLE (-7925 4850);
FORCEPROP 1 LAST PART_NUMBER CH5222KEB01
J 0
(-7925 4550);
DISPLAY 0.489362 (-7925 4550);
PAINT SKYBLUE (-7925 4550);
DISPLAY INVISIBLE (-7925 4550);
FORCEADD Q_RES..1
(-7350 4050);
FORCEPROP 1 LAST LOCATION PR320
J 0
(-7375 4100);
DISPLAY 0.489362 (-7375 4100);
PAINT SKYBLUE (-7375 4100);
FORCEPROP 0 LAST $SEC 1
J 0
(-7350 4125);
DISPLAY 0.680851 (-7350 4125);
PAINT MONO (-7350 4125);
DISPLAY INVISIBLE (-7350 4125);
FORCEPROP 0 LAST CDS_SEC 1
J 0
(-7350 4125);
DISPLAY 1.021277 (-7350 4125);
DISPLAY INVISIBLE (-7350 4125);
FORCEPROP 1 LASTPIN (-7450 4050) $PN 1
J 0
(-7438 4062);
DISPLAY 0.489362 (-7438 4062);
PAINT MONO (-7438 4062);
FORCEPROP 1 LASTPIN (-7250 4050) $PN 2
J 0
(-7288 4062);
DISPLAY 0.489362 (-7288 4062);
PAINT MONO (-7288 4062);
FORCEPROP 1 LAST TOLERANCE 1%
J 0
(-7225 4075);
DISPLAY 0.489362 (-7225 4075);
PAINT SKYBLUE (-7225 4075);
FORCEPROP 1 LAST VALUE 8.87K
J 2
(-7450 4075);
DISPLAY 0.489362 (-7450 4075);
PAINT SKYBLUE (-7450 4075);
FORCEPROP 1 LAST WATTAGE 1/16W
J 0
(-7250 3950);
DISPLAY 0.489362 (-7250 3950);
PAINT SKYBLUE (-7250 3950);
FORCEPROP 1 LAST PACK_TYPE 0402LF
J 0
(-7250 4000);
DISPLAY 0.489362 (-7250 4000);
PAINT SKYBLUE (-7250 4000);
FORCEPROP 1 LAST MATERIAL EMPTY
J 0
(-7650 3950);
DISPLAY 0.489362 (-7650 3950);
PAINT RED (-7650 3950);
FORCEPROP 2 LAST CDS_LIB pure_quanta
J 0
(-7350 4050);
DISPLAY INVISIBLE (-7350 4050);
FORCEPROP 1 LAST PATH I46
J 0
(-7400 4200);
DISPLAY 0.978723 (-7400 4200);
PAINT WHITE (-7400 4200);
DISPLAY INVISIBLE (-7400 4200);
FORCEPROP 1 LAST PART_NUMBER CS28872FB01
J 0
(-7625 4000);
DISPLAY 0.489362 (-7625 4000);
PAINT SKYBLUE (-7625 4000);
DISPLAY INVISIBLE (-7625 4000);
FORCEADD OFFPAGE..2
R 2
(-7350 4350);
FORCEPROP 2 LAST $XR0 193 
J 0
(-7605 4350);
DISPLAY 0.638298 (-7605 4350);
PAINT MONO (-7605 4350);
FORCEPROP 2 LAST CDS_LIB standard
J 2
(-7350 4350);
DISPLAY INVISIBLE (-7350 4350);
FORCEPROP 1 LAST OFFPAGE TRUE
J 2
(-7675 4225);
DISPLAY 0.872340 (-7675 4225);
PAINT GREEN (-7675 4225);
DISPLAY INVISIBLE (-7675 4225);
FORCEPROP 1 LAST COMMENT_BODY TRUE
J 2
(-7305 4255);
DISPLAY 0.872340 (-7305 4255);
PAINT GREEN (-7305 4255);
DISPLAY INVISIBLE (-7305 4255);
FORCEPROP 2 LAST PATH I47
J 0
(-7600 4400);
DISPLAY 0.680851 (-7600 4400);
DISPLAY INVISIBLE (-7600 4400);
FORCEADD UNIVERSAL_GND..1
(-7625 4950);
FORCEPROP 3 LASTPIN (-7625 5000) SIG_NAME GND\g
J 0
(-7615 5010);
DISPLAY 0.659574 (-7615 5010);
PAINT MONO (-7615 5010);
DISPLAY INVISIBLE (-7615 5010);
FORCEPROP 2 LAST CDS_LIB pure_quanta_power
J 0
(-7625 4950);
DISPLAY INVISIBLE (-7625 4950);
FORCEPROP 1 LAST HDL_POWER GND
J 1
(-7600 4875);
DISPLAY 0.872340 (-7600 4875);
PAINT GREEN (-7600 4875);
DISPLAY INVISIBLE (-7600 4875);
FORCEPROP 1 LAST PATH I48
J 0
(-7550 4950);
DISPLAY 0.872340 (-7550 4950);
PAINT AQUA (-7550 4950);
DISPLAY INVISIBLE (-7550 4950);
FORCEADD Q_RES..2
(-7975 5200);
FORCEPROP 1 LAST LOCATION PR318
J 0
(-7925 5325);
DISPLAY 0.489362 (-7925 5325);
PAINT SKYBLUE (-7925 5325);
FORCEPROP 0 LAST $SEC 1
J 0
(-7925 5350);
DISPLAY 0.680851 (-7925 5350);
PAINT MONO (-7925 5350);
DISPLAY INVISIBLE (-7925 5350);
FORCEPROP 0 LAST CDS_SEC 1
J 0
(-7925 5350);
DISPLAY 1.021277 (-7925 5350);
DISPLAY INVISIBLE (-7925 5350);
FORCEPROP 1 LASTPIN (-7975 5300) $PN 1
J 0
(-7960 5410);
DISPLAY 0.489362 (-7960 5410);
PAINT MONO (-7960 5410);
FORCEPROP 1 LASTPIN (-7975 5100) $PN 2
J 0
(-7970 5110);
DISPLAY 0.489362 (-7970 5110);
PAINT MONO (-7970 5110);
FORCEPROP 1 LAST WATTAGE 1/16W
J 0
(-7925 5175);
DISPLAY 0.489362 (-7925 5175);
PAINT SKYBLUE (-7925 5175);
FORCEPROP 1 LAST MATERIAL CHIP
J 0
(-7925 5125);
DISPLAY 0.489362 (-7925 5125);
PAINT SKYBLUE (-7925 5125);
FORCEPROP 1 LAST TOLERANCE 1%
J 0
(-7925 5225);
DISPLAY 0.489362 (-7925 5225);
PAINT SKYBLUE (-7925 5225);
FORCEPROP 1 LAST VALUE 2.2
J 0
(-7925 5275);
DISPLAY 0.489362 (-7925 5275);
PAINT SKYBLUE (-7925 5275);
FORCEPROP 1 LAST PACK_TYPE 0402LF
J 0
(-7925 5025);
DISPLAY 0.489362 (-7925 5025);
PAINT SKYBLUE (-7925 5025);
FORCEPROP 2 LAST CDS_LIB pure_quanta
J 0
(-7975 5200);
DISPLAY INVISIBLE (-7975 5200);
FORCEPROP 1 LAST PATH I49
J 0
(-7925 5375);
DISPLAY 0.978723 (-7925 5375);
PAINT WHITE (-7925 5375);
DISPLAY INVISIBLE (-7925 5375);
FORCEPROP 1 LAST PART_NUMBER CS-2202FB01
J 0
(-7925 5075);
DISPLAY 0.489362 (-7925 5075);
PAINT SKYBLUE (-7925 5075);
DISPLAY INVISIBLE (-7925 5075);
FORCEADD VCC_CORE..1
(-8625 5825);
FORCEPROP 3 LASTPIN (-8625 5775) SIG_NAME P5V_AUX\g
J 0
(-8615 5785);
DISPLAY 0.659574 (-8615 5785);
PAINT MONO (-8615 5785);
DISPLAY INVISIBLE (-8615 5785);
FORCEPROP 1 LAST HDL_POWER P5V_AUX
J 1
(-8625 5875);
DISPLAY 0.489362 (-8625 5875);
PAINT GREEN (-8625 5875);
FORCEPROP 2 LAST CDS_LIB pure_quanta_power
J 0
(-8625 5825);
DISPLAY INVISIBLE (-8625 5825);
FORCEPROP 1 LAST PATH I5
J 0
(-8575 5850);
DISPLAY 0.872340 (-8575 5850);
PAINT AQUA (-8575 5850);
DISPLAY INVISIBLE (-8575 5850);
FORCEADD VCC_CORE..1
(-7800 5825);
FORCEPROP 3 LASTPIN (-7800 5775) SIG_NAME PVDDCR_CPU0_P0_PVCC\g
J 0
(-7790 5785);
DISPLAY 0.659574 (-7790 5785);
PAINT MONO (-7790 5785);
DISPLAY INVISIBLE (-7790 5785);
FORCEPROP 1 LAST HDL_POWER PVDDCR_CPU0_P0_PVCC
J 1
(-7800 5875);
DISPLAY 0.489362 (-7800 5875);
PAINT GREEN (-7800 5875);
FORCEPROP 2 LAST CDS_LIB pure_quanta_power
J 0
(-7800 5825);
DISPLAY INVISIBLE (-7800 5825);
FORCEPROP 1 LAST PATH I50
J 0
(-7750 5850);
DISPLAY 0.872340 (-7750 5850);
PAINT AQUA (-7750 5850);
DISPLAY INVISIBLE (-7750 5850);
FORCEADD Q_CAP..1
(-7625 5200);
FORCEPROP 1 LAST LOCATION PC477_C0P0_1
J 0
(-7575 5300);
DISPLAY 0.489362 (-7575 5300);
PAINT SKYBLUE (-7575 5300);
FORCEPROP 0 LAST $SEC 1
J 0
(-7575 5325);
DISPLAY 0.680851 (-7575 5325);
PAINT MONO (-7575 5325);
DISPLAY INVISIBLE (-7575 5325);
FORCEPROP 0 LAST CDS_SEC 1
J 0
(-7575 5325);
DISPLAY 1.021277 (-7575 5325);
DISPLAY INVISIBLE (-7575 5325);
FORCEPROP 1 LASTPIN (-7625 5300) $PN 1
J 0
(-7615 5280);
DISPLAY 0.489362 (-7615 5280);
PAINT MONO (-7615 5280);
FORCEPROP 1 LASTPIN (-7625 5100) $PN 2
J 0
(-7615 5080);
DISPLAY 0.489362 (-7615 5080);
PAINT MONO (-7615 5080);
FORCEPROP 1 LAST VOLTAGE 10V
J 0
(-7575 5200);
DISPLAY 0.489362 (-7575 5200);
PAINT SKYBLUE (-7575 5200);
FORCEPROP 1 LAST VALUE 2.2UF
J 0
(-7575 5250);
DISPLAY 0.489362 (-7575 5250);
PAINT SKYBLUE (-7575 5250);
FORCEPROP 1 LAST TOLERANCE 10%
J 0
(-7575 5150);
DISPLAY 0.489362 (-7575 5150);
PAINT SKYBLUE (-7575 5150);
FORCEPROP 1 LAST MATERIAL X6S
J 0
(-7575 5100);
DISPLAY 0.489362 (-7575 5100);
PAINT SKYBLUE (-7575 5100);
FORCEPROP 1 LAST PACK_TYPE C0402
J 0
(-7575 5000);
DISPLAY 0.489362 (-7575 5000);
PAINT SKYBLUE (-7575 5000);
FORCEPROP 2 LAST CDS_LIB pure_quanta
J 0
(-7625 5200);
DISPLAY INVISIBLE (-7625 5200);
FORCEPROP 1 LAST PATH I51
J 0
(-7575 5350);
DISPLAY 0.978723 (-7575 5350);
PAINT WHITE (-7575 5350);
DISPLAY INVISIBLE (-7575 5350);
FORCEPROP 1 LAST PART_NUMBER CH5222KEB01
J 0
(-7575 5050);
DISPLAY 0.489362 (-7575 5050);
PAINT SKYBLUE (-7575 5050);
DISPLAY INVISIBLE (-7575 5050);
FORCEADD Q_CAP..1
(-5550 5225);
FORCEPROP 1 LAST LOCATION PC479_1
J 0
(-5500 5325);
DISPLAY 0.489362 (-5500 5325);
PAINT SKYBLUE (-5500 5325);
FORCEPROP 0 LAST $SEC 1
J 0
(-5500 5350);
DISPLAY 0.680851 (-5500 5350);
PAINT MONO (-5500 5350);
DISPLAY INVISIBLE (-5500 5350);
FORCEPROP 0 LAST CDS_SEC 1
J 0
(-5500 5350);
DISPLAY 1.021277 (-5500 5350);
DISPLAY INVISIBLE (-5500 5350);
FORCEPROP 1 LASTPIN (-5550 5325) $PN 1
J 0
(-5540 5305);
DISPLAY 0.489362 (-5540 5305);
PAINT MONO (-5540 5305);
FORCEPROP 1 LASTPIN (-5550 5125) $PN 2
J 0
(-5540 5105);
DISPLAY 0.489362 (-5540 5105);
PAINT MONO (-5540 5105);
FORCEPROP 1 LAST MATERIAL X7R
J 0
(-5500 5125);
DISPLAY 0.489362 (-5500 5125);
PAINT SKYBLUE (-5500 5125);
FORCEPROP 1 LAST VALUE 0.1UF
J 0
(-5500 5275);
DISPLAY 0.489362 (-5500 5275);
PAINT SKYBLUE (-5500 5275);
FORCEPROP 1 LAST VOLTAGE 25V
J 0
(-5500 5225);
DISPLAY 0.489362 (-5500 5225);
PAINT SKYBLUE (-5500 5225);
FORCEPROP 1 LAST PACK_TYPE 0402
J 0
(-5500 5025);
DISPLAY 0.489362 (-5500 5025);
PAINT SKYBLUE (-5500 5025);
FORCEPROP 1 LAST TOLERANCE 10%
J 0
(-5500 5175);
DISPLAY 0.489362 (-5500 5175);
PAINT SKYBLUE (-5500 5175);
FORCEPROP 2 LAST CDS_LIB pure_quanta
J 0
(-5550 5225);
DISPLAY INVISIBLE (-5550 5225);
FORCEPROP 1 LAST PATH I52
J 0
(-5500 5375);
DISPLAY 0.978723 (-5500 5375);
PAINT WHITE (-5500 5375);
DISPLAY INVISIBLE (-5500 5375);
FORCEPROP 1 LAST PART_NUMBER CH4104K1B00
J 0
(-5500 5075);
DISPLAY 0.489362 (-5500 5075);
PAINT SKYBLUE (-5500 5075);
DISPLAY INVISIBLE (-5500 5075);
FORCEADD Q_CAP..1
(-5225 5225);
FORCEPROP 1 LAST LOCATION PC481_1
J 0
(-5175 5325);
DISPLAY 0.510638 (-5175 5325);
FORCEPROP 0 LAST $SEC 1
J 0
(-5175 5350);
DISPLAY 0.680851 (-5175 5350);
PAINT MONO (-5175 5350);
DISPLAY INVISIBLE (-5175 5350);
FORCEPROP 0 LAST CDS_SEC 1
J 0
(-5175 5350);
DISPLAY 1.021277 (-5175 5350);
DISPLAY INVISIBLE (-5175 5350);
FORCEPROP 1 LASTPIN (-5225 5325) $PN 1
J 0
(-5215 5305);
DISPLAY 0.787234 (-5215 5305);
PAINT MONO (-5215 5305);
FORCEPROP 1 LASTPIN (-5225 5125) $PN 2
J 0
(-5215 5105);
DISPLAY 0.787234 (-5215 5105);
PAINT MONO (-5215 5105);
FORCEPROP 1 LAST VALUE 1UF
J 0
(-5175 5275);
DISPLAY 0.510638 (-5175 5275);
FORCEPROP 1 LAST VOLTAGE 25V
J 0
(-5175 5225);
DISPLAY 0.510638 (-5175 5225);
FORCEPROP 1 LAST TOLERANCE 10%
J 0
(-5175 5175);
DISPLAY 0.510638 (-5175 5175);
FORCEPROP 1 LAST MATERIAL X6S
J 0
(-5175 5125);
DISPLAY 0.510638 (-5175 5125);
FORCEPROP 1 LAST PACK_TYPE C0402
J 0
(-5175 5025);
DISPLAY 0.510638 (-5175 5025);
FORCEPROP 2 LAST CDS_LIB pure_quanta
J 0
(-5225 5225);
DISPLAY INVISIBLE (-5225 5225);
FORCEPROP 1 LAST PATH I53
J 0
(-5175 5375);
DISPLAY 0.978723 (-5175 5375);
PAINT WHITE (-5175 5375);
DISPLAY INVISIBLE (-5175 5375);
FORCEPROP 1 LAST PART_NUMBER CH5104KEB02
J 0
(-5175 5075);
DISPLAY 0.510638 (-5175 5075);
DISPLAY INVISIBLE (-5175 5075);
FORCEADD Q_CAP..1
(-4825 4175);
FORCEPROP 1 LAST LOCATION PC178
J 0
(-4775 4275);
DISPLAY 0.489362 (-4775 4275);
PAINT SKYBLUE (-4775 4275);
FORCEPROP 0 LAST $SEC 1
J 0
(-4775 4300);
DISPLAY 0.680851 (-4775 4300);
PAINT MONO (-4775 4300);
DISPLAY INVISIBLE (-4775 4300);
FORCEPROP 0 LAST CDS_SEC 1
J 0
(-4775 4300);
DISPLAY 1.021277 (-4775 4300);
DISPLAY INVISIBLE (-4775 4300);
FORCEPROP 1 LASTPIN (-4825 4275) $PN 1
J 0
(-4815 4255);
DISPLAY 0.489362 (-4815 4255);
PAINT MONO (-4815 4255);
FORCEPROP 1 LASTPIN (-4825 4075) $PN 2
J 0
(-4815 4055);
DISPLAY 0.489362 (-4815 4055);
PAINT MONO (-4815 4055);
FORCEPROP 1 LAST VALUE 560PF
J 0
(-4775 4225);
DISPLAY 0.489362 (-4775 4225);
PAINT SKYBLUE (-4775 4225);
FORCEPROP 1 LAST MATERIAL EMPTY
J 0
(-4775 4075);
DISPLAY 0.489362 (-4775 4075);
PAINT RED (-4775 4075);
FORCEPROP 1 LAST VOLTAGE 50V
J 0
(-4775 4175);
DISPLAY 0.489362 (-4775 4175);
PAINT SKYBLUE (-4775 4175);
FORCEPROP 1 LAST TOLERANCE 10%
J 0
(-4775 4125);
DISPLAY 0.489362 (-4775 4125);
PAINT SKYBLUE (-4775 4125);
FORCEPROP 1 LAST PACK_TYPE C0402
J 0
(-4775 3975);
DISPLAY 0.489362 (-4775 3975);
PAINT SKYBLUE (-4775 3975);
FORCEPROP 2 LAST CDS_LIB pure_quanta
J 0
(-4825 4175);
DISPLAY INVISIBLE (-4825 4175);
FORCEPROP 1 LAST PATH I54
J 0
(-4775 4325);
DISPLAY 0.978723 (-4775 4325);
PAINT WHITE (-4775 4325);
DISPLAY INVISIBLE (-4775 4325);
FORCEPROP 1 LAST PART_NUMBER CH1566K1B09
J 0
(-4775 4025);
DISPLAY 0.489362 (-4775 4025);
PAINT SKYBLUE (-4775 4025);
DISPLAY INVISIBLE (-4775 4025);
FORCEADD Q_RES..1
(-4850 4700);
FORCEPROP 1 LAST LOCATION PR322
J 0
(-4900 4750);
DISPLAY 0.489362 (-4900 4750);
PAINT SKYBLUE (-4900 4750);
FORCEPROP 0 LAST $SEC 1
J 0
(-4825 4775);
DISPLAY 0.680851 (-4825 4775);
PAINT MONO (-4825 4775);
DISPLAY INVISIBLE (-4825 4775);
FORCEPROP 0 LAST CDS_SEC 1
J 0
(-4825 4775);
DISPLAY 1.021277 (-4825 4775);
DISPLAY INVISIBLE (-4825 4775);
FORCEPROP 1 LASTPIN (-4950 4700) $PN 1
J 0
(-4938 4712);
DISPLAY 0.489362 (-4938 4712);
PAINT MONO (-4938 4712);
FORCEPROP 1 LASTPIN (-4750 4700) $PN 2
J 0
(-4788 4712);
DISPLAY 0.489362 (-4788 4712);
PAINT MONO (-4788 4712);
FORCEPROP 1 LAST WATTAGE 1/16W
J 0
(-4750 4650);
DISPLAY 0.489362 (-4750 4650);
PAINT SKYBLUE (-4750 4650);
FORCEPROP 1 LAST TOLERANCE 1%
J 0
(-4750 4725);
DISPLAY 0.489362 (-4750 4725);
PAINT SKYBLUE (-4750 4725);
FORCEPROP 1 LAST VALUE 5.6
J 2
(-4950 4725);
DISPLAY 0.489362 (-4950 4725);
PAINT SKYBLUE (-4950 4725);
FORCEPROP 1 LAST MATERIAL CHIP
J 0
(-5100 4600);
DISPLAY 0.489362 (-5100 4600);
PAINT SKYBLUE (-5100 4600);
FORCEPROP 1 LAST PACK_TYPE 0402LF
J 0
(-4750 4600);
DISPLAY 0.489362 (-4750 4600);
PAINT SKYBLUE (-4750 4600);
FORCEPROP 2 LAST CDS_LIB pure_quanta
J 0
(-4850 4700);
DISPLAY INVISIBLE (-4850 4700);
FORCEPROP 1 LAST PATH I55
J 0
(-4900 4850);
DISPLAY 0.978723 (-4900 4850);
PAINT WHITE (-4900 4850);
DISPLAY INVISIBLE (-4900 4850);
FORCEPROP 1 LAST PART_NUMBER CS-5602FB01
J 0
(-5100 4650);
DISPLAY 0.489362 (-5100 4650);
PAINT SKYBLUE (-5100 4650);
DISPLAY INVISIBLE (-5100 4650);
FORCEADD OFFPAGE..3
R 2
(-4350 4100);
FORCEPROP 2 LAST $XR0 196 
J 0
(-4804 4100);
DISPLAY 0.638298 (-4804 4100);
PAINT MONO (-4804 4100);
FORCEPROP 2 LAST CDS_LIB standard
J 0
(-4350 4100);
DISPLAY INVISIBLE (-4350 4100);
FORCEPROP 1 LAST OFFPAGE TRUE
J 2
(-4675 3975);
DISPLAY 0.872340 (-4675 3975);
PAINT GREEN (-4675 3975);
DISPLAY INVISIBLE (-4675 3975);
FORCEPROP 1 LAST COMMENT_BODY TRUE
J 2
(-4300 4000);
DISPLAY 0.872340 (-4300 4000);
PAINT GREEN (-4300 4000);
DISPLAY INVISIBLE (-4300 4000);
FORCEPROP 2 LAST PATH I56
J 0
(-4800 4150);
DISPLAY 0.680851 (-4800 4150);
DISPLAY INVISIBLE (-4800 4150);
FORCEADD Q_CAP..1
(-4900 5225);
FORCEPROP 1 LAST LOCATION PC483_1
J 0
(-4850 5325);
DISPLAY 0.489362 (-4850 5325);
PAINT SKYBLUE (-4850 5325);
FORCEPROP 0 LAST $SEC 1
J 0
(-4850 5350);
DISPLAY 0.680851 (-4850 5350);
PAINT MONO (-4850 5350);
DISPLAY INVISIBLE (-4850 5350);
FORCEPROP 0 LAST CDS_SEC 1
J 0
(-4850 5350);
DISPLAY 1.021277 (-4850 5350);
DISPLAY INVISIBLE (-4850 5350);
FORCEPROP 1 LASTPIN (-4900 5325) $PN 1
J 0
(-4890 5305);
DISPLAY 0.489362 (-4890 5305);
PAINT MONO (-4890 5305);
FORCEPROP 1 LASTPIN (-4900 5125) $PN 2
J 0
(-4890 5105);
DISPLAY 0.489362 (-4890 5105);
PAINT MONO (-4890 5105);
FORCEPROP 1 LAST PACK_TYPE C0805
J 0
(-4850 5025);
DISPLAY 0.489362 (-4850 5025);
PAINT SKYBLUE (-4850 5025);
FORCEPROP 1 LAST VOLTAGE 16V
J 0
(-4850 5225);
DISPLAY 0.489362 (-4850 5225);
PAINT SKYBLUE (-4850 5225);
FORCEPROP 1 LAST VALUE 22UF
J 0
(-4850 5275);
DISPLAY 0.489362 (-4850 5275);
PAINT SKYBLUE (-4850 5275);
FORCEPROP 1 LAST TOLERANCE 20%
J 0
(-4850 5175);
DISPLAY 0.489362 (-4850 5175);
PAINT SKYBLUE (-4850 5175);
FORCEPROP 1 LAST MATERIAL X6S
J 0
(-4850 5125);
DISPLAY 0.489362 (-4850 5125);
PAINT SKYBLUE (-4850 5125);
FORCEPROP 2 LAST CDS_LIB pure_quanta
J 0
(-4900 5225);
DISPLAY INVISIBLE (-4900 5225);
FORCEPROP 1 LAST PATH I57
J 0
(-4850 5375);
DISPLAY 0.978723 (-4850 5375);
PAINT WHITE (-4850 5375);
DISPLAY INVISIBLE (-4850 5375);
FORCEPROP 1 LAST PART_NUMBER CH6223MEA01
J 0
(-4850 5075);
DISPLAY 0.489362 (-4850 5075);
PAINT SKYBLUE (-4850 5075);
DISPLAY INVISIBLE (-4850 5075);
FORCEADD Q_CAP..1
(-4575 5225);
FORCEPROP 1 LAST LOCATION PC485_1
J 0
(-4525 5325);
DISPLAY 0.489362 (-4525 5325);
PAINT SKYBLUE (-4525 5325);
FORCEPROP 0 LAST $SEC 1
J 0
(-4525 5350);
DISPLAY 0.680851 (-4525 5350);
PAINT MONO (-4525 5350);
DISPLAY INVISIBLE (-4525 5350);
FORCEPROP 0 LAST CDS_SEC 1
J 0
(-4525 5350);
DISPLAY 1.021277 (-4525 5350);
DISPLAY INVISIBLE (-4525 5350);
FORCEPROP 1 LASTPIN (-4575 5325) $PN 1
J 0
(-4565 5305);
DISPLAY 0.489362 (-4565 5305);
PAINT MONO (-4565 5305);
FORCEPROP 1 LASTPIN (-4575 5125) $PN 2
J 0
(-4565 5105);
DISPLAY 0.489362 (-4565 5105);
PAINT MONO (-4565 5105);
FORCEPROP 1 LAST PACK_TYPE C0805
J 0
(-4525 5025);
DISPLAY 0.489362 (-4525 5025);
PAINT SKYBLUE (-4525 5025);
FORCEPROP 1 LAST VALUE 22UF
J 0
(-4525 5275);
DISPLAY 0.489362 (-4525 5275);
PAINT SKYBLUE (-4525 5275);
FORCEPROP 1 LAST TOLERANCE 20%
J 0
(-4525 5175);
DISPLAY 0.489362 (-4525 5175);
PAINT SKYBLUE (-4525 5175);
FORCEPROP 1 LAST VOLTAGE 16V
J 0
(-4525 5225);
DISPLAY 0.489362 (-4525 5225);
PAINT SKYBLUE (-4525 5225);
FORCEPROP 1 LAST MATERIAL X6S
J 0
(-4525 5125);
DISPLAY 0.489362 (-4525 5125);
PAINT SKYBLUE (-4525 5125);
FORCEPROP 2 LAST CDS_LIB pure_quanta
J 0
(-4575 5225);
DISPLAY INVISIBLE (-4575 5225);
FORCEPROP 1 LAST PATH I58
J 0
(-4525 5375);
DISPLAY 0.978723 (-4525 5375);
PAINT WHITE (-4525 5375);
DISPLAY INVISIBLE (-4525 5375);
FORCEPROP 1 LAST PART_NUMBER CH6223MEA01
J 0
(-4525 5075);
DISPLAY 0.489362 (-4525 5075);
PAINT SKYBLUE (-4525 5075);
DISPLAY INVISIBLE (-4525 5075);
FORCEADD Q_CAP..1
(-4275 5225);
FORCEPROP 1 LAST LOCATION PC487_1
J 0
(-4225 5325);
DISPLAY 0.489362 (-4225 5325);
PAINT SKYBLUE (-4225 5325);
FORCEPROP 0 LAST $SEC 1
J 0
(-4225 5350);
DISPLAY 0.680851 (-4225 5350);
PAINT MONO (-4225 5350);
DISPLAY INVISIBLE (-4225 5350);
FORCEPROP 0 LAST CDS_SEC 1
J 0
(-4225 5350);
DISPLAY 1.021277 (-4225 5350);
DISPLAY INVISIBLE (-4225 5350);
FORCEPROP 1 LASTPIN (-4275 5325) $PN 1
J 0
(-4265 5305);
DISPLAY 0.489362 (-4265 5305);
PAINT MONO (-4265 5305);
FORCEPROP 1 LASTPIN (-4275 5125) $PN 2
J 0
(-4265 5105);
DISPLAY 0.489362 (-4265 5105);
PAINT MONO (-4265 5105);
FORCEPROP 1 LAST VALUE 22UF
J 0
(-4225 5275);
DISPLAY 0.489362 (-4225 5275);
PAINT SKYBLUE (-4225 5275);
FORCEPROP 1 LAST VOLTAGE 16V
J 0
(-4225 5225);
DISPLAY 0.489362 (-4225 5225);
PAINT SKYBLUE (-4225 5225);
FORCEPROP 1 LAST MATERIAL X6S
J 0
(-4225 5125);
DISPLAY 0.489362 (-4225 5125);
PAINT SKYBLUE (-4225 5125);
FORCEPROP 1 LAST PACK_TYPE C0805
J 0
(-4225 5025);
DISPLAY 0.489362 (-4225 5025);
PAINT SKYBLUE (-4225 5025);
FORCEPROP 1 LAST TOLERANCE 20%
J 0
(-4225 5175);
DISPLAY 0.489362 (-4225 5175);
PAINT SKYBLUE (-4225 5175);
FORCEPROP 2 LAST CDS_LIB pure_quanta
J 0
(-4275 5225);
DISPLAY INVISIBLE (-4275 5225);
FORCEPROP 1 LAST PATH I59
J 0
(-4225 5375);
DISPLAY 0.978723 (-4225 5375);
PAINT WHITE (-4225 5375);
DISPLAY INVISIBLE (-4225 5375);
FORCEPROP 1 LAST PART_NUMBER CH6223MEA01
J 0
(-4225 5075);
DISPLAY 0.489362 (-4225 5075);
PAINT SKYBLUE (-4225 5075);
DISPLAY INVISIBLE (-4225 5075);
FORCEADD VCC_CORE..1
(-8275 5825);
FORCEPROP 3 LASTPIN (-8275 5775) SIG_NAME P3V3_AUX\g
J 0
(-8265 5785);
DISPLAY 0.659574 (-8265 5785);
PAINT MONO (-8265 5785);
DISPLAY INVISIBLE (-8265 5785);
FORCEPROP 1 LAST HDL_POWER P3V3_AUX
J 1
(-8275 5875);
DISPLAY 0.489362 (-8275 5875);
PAINT GREEN (-8275 5875);
FORCEPROP 2 LAST CDS_LIB pure_quanta_power
J 0
(-8275 5825);
DISPLAY INVISIBLE (-8275 5825);
FORCEPROP 1 LAST PATH I6
J 0
(-8225 5850);
DISPLAY 0.872340 (-8225 5850);
PAINT AQUA (-8225 5850);
DISPLAY INVISIBLE (-8225 5850);
FORCEADD OFFPAGE..3
R 2
(-3950 1350);
FORCEPROP 2 LAST $XR0 194 
J 0
(-4230 1350);
DISPLAY 0.638298 (-4230 1350);
PAINT MONO (-4230 1350);
FORCEPROP 2 LAST CDS_LIB standard
J 2
(-3950 1350);
DISPLAY INVISIBLE (-3950 1350);
FORCEPROP 1 LAST OFFPAGE TRUE
J 2
(-4275 1225);
DISPLAY 0.872340 (-4275 1225);
PAINT GREEN (-4275 1225);
DISPLAY INVISIBLE (-4275 1225);
FORCEPROP 1 LAST COMMENT_BODY TRUE
J 2
(-3900 1250);
DISPLAY 0.872340 (-3900 1250);
PAINT GREEN (-3900 1250);
DISPLAY INVISIBLE (-3900 1250);
FORCEPROP 2 LAST PATH I60
J 0
(-4225 1400);
DISPLAY 0.680851 (-4225 1400);
DISPLAY INVISIBLE (-4225 1400);
FORCEADD Q_CAP..1
(-3750 1825);
FORCEPROP 1 LAST LOCATION PC490
J 0
(-3700 1950);
DISPLAY 0.489362 (-3700 1950);
PAINT SKYBLUE (-3700 1950);
FORCEPROP 0 LAST $SEC 1
J 0
(-3700 1975);
DISPLAY 0.680851 (-3700 1975);
PAINT MONO (-3700 1975);
DISPLAY INVISIBLE (-3700 1975);
FORCEPROP 0 LAST CDS_SEC 1
J 0
(-3700 1975);
DISPLAY 1.021277 (-3700 1975);
DISPLAY INVISIBLE (-3700 1975);
FORCEPROP 1 LASTPIN (-3750 1925) $PN 1
J 0
(-3740 1905);
DISPLAY 0.489362 (-3740 1905);
PAINT MONO (-3740 1905);
FORCEPROP 1 LASTPIN (-3750 1725) $PN 2
J 0
(-3740 1705);
DISPLAY 0.489362 (-3740 1705);
PAINT MONO (-3740 1705);
FORCEPROP 1 LAST PACK_TYPE 0402
J 0
(-3700 1650);
DISPLAY 0.489362 (-3700 1650);
PAINT SKYBLUE (-3700 1650);
FORCEPROP 1 LAST MATERIAL X7R
J 0
(-3700 1750);
DISPLAY 0.489362 (-3700 1750);
PAINT SKYBLUE (-3700 1750);
FORCEPROP 1 LAST VALUE 0.22UF
J 0
(-3700 1900);
DISPLAY 0.489362 (-3700 1900);
PAINT SKYBLUE (-3700 1900);
FORCEPROP 1 LAST VOLTAGE 16V
J 0
(-3700 1850);
DISPLAY 0.489362 (-3700 1850);
PAINT SKYBLUE (-3700 1850);
FORCEPROP 1 LAST TOLERANCE 10%
J 0
(-3700 1800);
DISPLAY 0.489362 (-3700 1800);
PAINT SKYBLUE (-3700 1800);
FORCEPROP 2 LAST CDS_LIB pure_quanta
J 0
(-3750 1825);
DISPLAY INVISIBLE (-3750 1825);
FORCEPROP 1 LAST PATH I61
J 0
(-3700 1975);
DISPLAY 0.978723 (-3700 1975);
PAINT WHITE (-3700 1975);
DISPLAY INVISIBLE (-3700 1975);
FORCEPROP 1 LAST PART_NUMBER CH4223K1B00
J 0
(-3700 1675);
DISPLAY 0.489362 (-3700 1675);
PAINT SKYBLUE (-3700 1675);
DISPLAY INVISIBLE (-3700 1675);
FORCEADD Q_INDUCTOR4P_14..1
(-3075 1475);
FORCEPROP 1 LAST LOCATION PL52
J 0
(-3300 1730);
DISPLAY 0.489362 (-3300 1730);
PAINT SKYBLUE (-3300 1730);
FORCEPROP 0 LAST $SEC 1
J 0
(-3300 1875);
DISPLAY 0.680851 (-3300 1875);
PAINT MONO (-3300 1875);
DISPLAY INVISIBLE (-3300 1875);
FORCEPROP 0 LAST CDS_SEC 1
J 0
(-3300 1875);
DISPLAY 1.021277 (-3300 1875);
DISPLAY INVISIBLE (-3300 1875);
FORCEPROP 0 LASTPIN (-3475 1600) $PN 1
J 2
(-3485 1610);
DISPLAY 0.489362 (-3485 1610);
PAINT MONO (-3485 1610);
FORCEPROP 0 LASTPIN (-3475 1350) $PN 2
J 2
(-3485 1360);
DISPLAY 0.489362 (-3485 1360);
PAINT MONO (-3485 1360);
FORCEPROP 0 LASTPIN (-2675 1350) $PN 3
J 0
(-2665 1360);
DISPLAY 0.489362 (-2665 1360);
PAINT MONO (-2665 1360);
FORCEPROP 0 LASTPIN (-2675 1600) $PN 4
J 0
(-2665 1610);
DISPLAY 0.489362 (-2665 1610);
PAINT MONO (-2665 1610);
FORCEPROP 2 LAST VALUE 150NH
J 0
(-3300 1775);
DISPLAY 0.489362 (-3300 1775);
PAINT SKYBLUE (-3300 1775);
FORCEPROP 1 LAST MATERIAL IND
J 0
(-3300 1685);
DISPLAY 0.489362 (-3300 1685);
PAINT SKYBLUE (-3300 1685);
FORCEPROP 2 LAST PART_TYPE SMLF
J 0
(-3300 1825);
DISPLAY 1.021277 (-3300 1825);
FORCEPROP 2 LAST CDS_LIB pure_quanta
J 0
(-3075 1475);
DISPLAY INVISIBLE (-3075 1475);
FORCEPROP 1 LAST NEEDS_NO_SIZE TRUE
J 0
(-3075 1475);
DISPLAY 0.468085 (-3075 1475);
PAINT GREEN (-3075 1475);
DISPLAY INVISIBLE (-3075 1475);
FORCEPROP 1 LAST PATH I62
J 0
(-2875 1630);
DISPLAY 0.723404 (-2875 1630);
PAINT GREEN (-2875 1630);
DISPLAY INVISIBLE (-2875 1630);
FORCEPROP 1 LAST PART_NUMBER CV+15^0TZ04
J 0
(-3300 1635);
DISPLAY 0.489362 (-3300 1635);
PAINT SKYBLUE (-3300 1635);
DISPLAY INVISIBLE (-3300 1635);
FORCEADD OFFPAGE..3
(-2175 1350);
FORCEPROP 2 LAST $XR0 195 
J 0
(-1901 1350);
DISPLAY 0.638298 (-1901 1350);
PAINT MONO (-1901 1350);
FORCEPROP 2 LAST CDS_LIB standard
J 0
(-2175 1350);
DISPLAY INVISIBLE (-2175 1350);
FORCEPROP 1 LAST OFFPAGE TRUE
J 0
(-1850 1225);
DISPLAY 0.872340 (-1850 1225);
PAINT GREEN (-1850 1225);
DISPLAY INVISIBLE (-1850 1225);
FORCEPROP 1 LAST COMMENT_BODY TRUE
J 0
(-2225 1250);
DISPLAY 0.872340 (-2225 1250);
PAINT GREEN (-2225 1250);
DISPLAY INVISIBLE (-2225 1250);
FORCEPROP 2 LAST PATH I63
J 0
(-1900 1400);
DISPLAY 0.680851 (-1900 1400);
DISPLAY INVISIBLE (-1900 1400);
FORCEADD Q_CAPP..1
(-3175 2800);
FORCEPROP 1 LAST LOCATION PC108
J 0
(-3125 2900);
DISPLAY 0.489362 (-3125 2900);
PAINT SKYBLUE (-3125 2900);
FORCEPROP 0 LAST $SEC 1
J 0
(-3125 2925);
DISPLAY 0.680851 (-3125 2925);
PAINT MONO (-3125 2925);
DISPLAY INVISIBLE (-3125 2925);
FORCEPROP 0 LAST CDS_SEC 1
J 0
(-3125 2925);
DISPLAY 1.021277 (-3125 2925);
DISPLAY INVISIBLE (-3125 2925);
FORCEPROP 1 LASTPIN (-3175 2900) $PN 1
J 0
(-3165 2885);
DISPLAY 0.489362 (-3165 2885);
PAINT MONO (-3165 2885);
FORCEPROP 1 LASTPIN (-3175 2700) $PN 2
J 0
(-3165 2685);
DISPLAY 0.489362 (-3165 2685);
PAINT MONO (-3165 2685);
FORCEPROP 1 LAST VOLTAGE 4V
J 0
(-3125 2750);
DISPLAY 0.489362 (-3125 2750);
PAINT SKYBLUE (-3125 2750);
FORCEPROP 1 LAST PACK_TYPE SMLF
J 0
(-3125 2650);
DISPLAY 0.489362 (-3125 2650);
PAINT SKYBLUE (-3125 2650);
FORCEPROP 1 LAST MATERIAL SPCAP
J 0
(-3125 2700);
DISPLAY 0.489362 (-3125 2700);
PAINT SKYBLUE (-3125 2700);
FORCEPROP 1 LAST TOLERANCE 20%
J 0
(-3125 2800);
DISPLAY 0.489362 (-3125 2800);
PAINT SKYBLUE (-3125 2800);
FORCEPROP 1 LAST VALUE 220UF
J 0
(-3125 2850);
DISPLAY 0.489362 (-3125 2850);
PAINT SKYBLUE (-3125 2850);
FORCEPROP 2 LAST CDS_LIB pure_quanta
J 0
(-3175 2800);
DISPLAY INVISIBLE (-3175 2800);
FORCEPROP 1 LAST PATH I64
J 0
(-3125 2950);
DISPLAY 0.978723 (-3125 2950);
DISPLAY INVISIBLE (-3125 2950);
FORCEPROP 1 LAST PART_NUMBER CH122KM8801
J 0
(-3125 2600);
DISPLAY 0.489362 (-3125 2600);
PAINT SKYBLUE (-3125 2600);
DISPLAY INVISIBLE (-3125 2600);
FORCEADD Q_CAPP..1
(-2825 2800);
FORCEPROP 1 LAST LOCATION PC494
J 0
(-2775 2900);
DISPLAY 0.489362 (-2775 2900);
PAINT SKYBLUE (-2775 2900);
FORCEPROP 0 LAST $SEC 1
J 0
(-2775 2925);
DISPLAY 0.680851 (-2775 2925);
PAINT MONO (-2775 2925);
DISPLAY INVISIBLE (-2775 2925);
FORCEPROP 0 LAST CDS_SEC 1
J 0
(-2775 2925);
DISPLAY 1.021277 (-2775 2925);
DISPLAY INVISIBLE (-2775 2925);
FORCEPROP 1 LASTPIN (-2825 2900) $PN 1
J 0
(-2815 2885);
DISPLAY 0.489362 (-2815 2885);
PAINT MONO (-2815 2885);
FORCEPROP 1 LASTPIN (-2825 2700) $PN 2
J 0
(-2815 2685);
DISPLAY 0.489362 (-2815 2685);
PAINT MONO (-2815 2685);
FORCEPROP 1 LAST TOLERANCE 20%
J 0
(-2775 2800);
DISPLAY 0.489362 (-2775 2800);
PAINT SKYBLUE (-2775 2800);
FORCEPROP 1 LAST VALUE 220UF
J 0
(-2775 2850);
DISPLAY 0.489362 (-2775 2850);
PAINT SKYBLUE (-2775 2850);
FORCEPROP 1 LAST VOLTAGE 4V
J 0
(-2775 2750);
DISPLAY 0.489362 (-2775 2750);
PAINT SKYBLUE (-2775 2750);
FORCEPROP 1 LAST MATERIAL SPCAP
J 0
(-2775 2700);
DISPLAY 0.489362 (-2775 2700);
PAINT SKYBLUE (-2775 2700);
FORCEPROP 1 LAST PACK_TYPE SMLF
J 0
(-2775 2650);
DISPLAY 0.489362 (-2775 2650);
PAINT SKYBLUE (-2775 2650);
FORCEPROP 2 LAST CDS_LIB pure_quanta
J 0
(-2825 2800);
DISPLAY INVISIBLE (-2825 2800);
FORCEPROP 1 LAST PATH I65
J 0
(-2775 2950);
DISPLAY 0.978723 (-2775 2950);
DISPLAY INVISIBLE (-2775 2950);
FORCEPROP 1 LAST PART_NUMBER CH122KM8801
J 0
(-2775 2600);
DISPLAY 0.489362 (-2775 2600);
PAINT SKYBLUE (-2775 2600);
DISPLAY INVISIBLE (-2775 2600);
FORCEADD Q_CAPP..1
(-2500 2800);
FORCEPROP 1 LAST LOCATION PC495
J 0
(-2450 2900);
DISPLAY 0.489362 (-2450 2900);
PAINT SKYBLUE (-2450 2900);
FORCEPROP 0 LAST $SEC 1
J 0
(-2450 2925);
DISPLAY 0.680851 (-2450 2925);
PAINT MONO (-2450 2925);
DISPLAY INVISIBLE (-2450 2925);
FORCEPROP 0 LAST CDS_SEC 1
J 0
(-2450 2925);
DISPLAY 1.021277 (-2450 2925);
DISPLAY INVISIBLE (-2450 2925);
FORCEPROP 1 LASTPIN (-2500 2900) $PN 1
J 0
(-2490 2885);
DISPLAY 0.489362 (-2490 2885);
PAINT MONO (-2490 2885);
FORCEPROP 1 LASTPIN (-2500 2700) $PN 2
J 0
(-2490 2685);
DISPLAY 0.489362 (-2490 2685);
PAINT MONO (-2490 2685);
FORCEPROP 1 LAST PACK_TYPE SMLF
J 0
(-2450 2650);
DISPLAY 0.489362 (-2450 2650);
PAINT SKYBLUE (-2450 2650);
FORCEPROP 1 LAST MATERIAL SPCAP
J 0
(-2450 2700);
DISPLAY 0.489362 (-2450 2700);
PAINT SKYBLUE (-2450 2700);
FORCEPROP 1 LAST VALUE 220UF
J 0
(-2450 2850);
DISPLAY 0.489362 (-2450 2850);
PAINT SKYBLUE (-2450 2850);
FORCEPROP 1 LAST TOLERANCE 20%
J 0
(-2450 2800);
DISPLAY 0.489362 (-2450 2800);
PAINT SKYBLUE (-2450 2800);
FORCEPROP 1 LAST VOLTAGE 4V
J 0
(-2450 2750);
DISPLAY 0.489362 (-2450 2750);
PAINT SKYBLUE (-2450 2750);
FORCEPROP 2 LAST CDS_LIB pure_quanta
J 0
(-2500 2800);
DISPLAY INVISIBLE (-2500 2800);
FORCEPROP 1 LAST PATH I66
J 0
(-2450 2950);
DISPLAY 0.978723 (-2450 2950);
DISPLAY INVISIBLE (-2450 2950);
FORCEPROP 1 LAST PART_NUMBER CH122KM8801
J 0
(-2450 2600);
DISPLAY 0.489362 (-2450 2600);
PAINT SKYBLUE (-2450 2600);
DISPLAY INVISIBLE (-2450 2600);
FORCEADD Q_CAPP..1
(-2175 2800);
FORCEPROP 1 LAST LOCATION PC496
J 0
(-2125 2900);
DISPLAY 0.489362 (-2125 2900);
PAINT SKYBLUE (-2125 2900);
FORCEPROP 0 LAST $SEC 1
J 0
(-2125 2925);
DISPLAY 0.680851 (-2125 2925);
PAINT MONO (-2125 2925);
DISPLAY INVISIBLE (-2125 2925);
FORCEPROP 0 LAST CDS_SEC 1
J 0
(-2125 2925);
DISPLAY 1.021277 (-2125 2925);
DISPLAY INVISIBLE (-2125 2925);
FORCEPROP 1 LASTPIN (-2175 2900) $PN 1
J 0
(-2165 2885);
DISPLAY 0.489362 (-2165 2885);
PAINT MONO (-2165 2885);
FORCEPROP 1 LASTPIN (-2175 2700) $PN 2
J 0
(-2165 2685);
DISPLAY 0.489362 (-2165 2685);
PAINT MONO (-2165 2685);
FORCEPROP 1 LAST VALUE 220UF
J 0
(-2125 2850);
DISPLAY 0.489362 (-2125 2850);
PAINT SKYBLUE (-2125 2850);
FORCEPROP 1 LAST VOLTAGE 4V
J 0
(-2125 2750);
DISPLAY 0.489362 (-2125 2750);
PAINT SKYBLUE (-2125 2750);
FORCEPROP 1 LAST PACK_TYPE SMLF
J 0
(-2125 2650);
DISPLAY 0.489362 (-2125 2650);
PAINT SKYBLUE (-2125 2650);
FORCEPROP 1 LAST TOLERANCE 20%
J 0
(-2125 2800);
DISPLAY 0.489362 (-2125 2800);
PAINT SKYBLUE (-2125 2800);
FORCEPROP 1 LAST MATERIAL SPCAP
J 0
(-2125 2700);
DISPLAY 0.489362 (-2125 2700);
PAINT SKYBLUE (-2125 2700);
FORCEPROP 2 LAST CDS_LIB pure_quanta
J 0
(-2175 2800);
DISPLAY INVISIBLE (-2175 2800);
FORCEPROP 1 LAST PATH I67
J 0
(-2125 2950);
DISPLAY 0.978723 (-2125 2950);
DISPLAY INVISIBLE (-2125 2950);
FORCEPROP 1 LAST PART_NUMBER CH122KM8801
J 0
(-2125 2600);
DISPLAY 0.489362 (-2125 2600);
PAINT SKYBLUE (-2125 2600);
DISPLAY INVISIBLE (-2125 2600);
FORCEADD Q_CAP..1
(-1725 1425);
FORCEPROP 1 LAST LOCATION PC499_2
J 0
(-1675 1525);
DISPLAY 0.489362 (-1675 1525);
PAINT SKYBLUE (-1675 1525);
FORCEPROP 0 LAST $SEC 1
J 0
(-1675 1550);
DISPLAY 0.680851 (-1675 1550);
PAINT MONO (-1675 1550);
DISPLAY INVISIBLE (-1675 1550);
FORCEPROP 0 LAST CDS_SEC 1
J 0
(-1675 1550);
DISPLAY 1.021277 (-1675 1550);
DISPLAY INVISIBLE (-1675 1550);
FORCEPROP 1 LASTPIN (-1725 1525) $PN 1
J 0
(-1715 1505);
DISPLAY 0.489362 (-1715 1505);
PAINT MONO (-1715 1505);
FORCEPROP 1 LASTPIN (-1725 1325) $PN 2
J 0
(-1715 1305);
DISPLAY 0.489362 (-1715 1305);
PAINT MONO (-1715 1305);
FORCEPROP 1 LAST VALUE 22UF
J 0
(-1675 1475);
DISPLAY 0.489362 (-1675 1475);
PAINT SKYBLUE (-1675 1475);
FORCEPROP 1 LAST VOLTAGE 4V
J 0
(-1675 1425);
DISPLAY 0.489362 (-1675 1425);
PAINT SKYBLUE (-1675 1425);
FORCEPROP 1 LAST PACK_TYPE C0805
J 0
(-1675 1225);
DISPLAY 0.489362 (-1675 1225);
PAINT SKYBLUE (-1675 1225);
FORCEPROP 1 LAST MATERIAL X6S
J 0
(-1675 1325);
DISPLAY 0.489362 (-1675 1325);
PAINT SKYBLUE (-1675 1325);
FORCEPROP 1 LAST TOLERANCE 20%
J 0
(-1675 1375);
DISPLAY 0.489362 (-1675 1375);
PAINT SKYBLUE (-1675 1375);
FORCEPROP 2 LAST CDS_LIB pure_quanta
J 0
(-1725 1425);
DISPLAY INVISIBLE (-1725 1425);
FORCEPROP 1 LAST PATH I68
J 0
(-1675 1575);
DISPLAY 0.978723 (-1675 1575);
PAINT WHITE (-1675 1575);
DISPLAY INVISIBLE (-1675 1575);
FORCEPROP 1 LAST PART_NUMBER CH622KMEA03
J 0
(-1675 1275);
DISPLAY 0.489362 (-1675 1275);
PAINT SKYBLUE (-1675 1275);
DISPLAY INVISIBLE (-1675 1275);
FORCEADD UNIVERSAL_GND..1
(-1300 1075);
FORCEPROP 3 LASTPIN (-1300 1125) SIG_NAME GND\g
J 0
(-1290 1135);
DISPLAY 0.659574 (-1290 1135);
PAINT MONO (-1290 1135);
DISPLAY INVISIBLE (-1290 1135);
FORCEPROP 2 LAST CDS_LIB pure_quanta_power
J 0
(-1300 1075);
DISPLAY INVISIBLE (-1300 1075);
FORCEPROP 1 LAST HDL_POWER GND
J 1
(-1275 1000);
DISPLAY 0.872340 (-1275 1000);
PAINT GREEN (-1275 1000);
DISPLAY INVISIBLE (-1275 1000);
FORCEPROP 1 LAST PATH I69
J 0
(-1225 1075);
DISPLAY 0.872340 (-1225 1075);
PAINT AQUA (-1225 1075);
DISPLAY INVISIBLE (-1225 1075);
FORCEADD UNIVERSAL_GND..1
(-8000 1050);
FORCEPROP 3 LASTPIN (-8000 1100) SIG_NAME GND\g
J 0
(-7990 1110);
DISPLAY 0.659574 (-7990 1110);
PAINT MONO (-7990 1110);
DISPLAY INVISIBLE (-7990 1110);
FORCEPROP 2 LAST CDS_LIB pure_quanta_power
J 0
(-8000 1050);
DISPLAY INVISIBLE (-8000 1050);
FORCEPROP 1 LAST HDL_POWER GND
J 1
(-7975 975);
DISPLAY 0.872340 (-7975 975);
PAINT GREEN (-7975 975);
DISPLAY INVISIBLE (-7975 975);
FORCEPROP 1 LAST PATH I7
J 0
(-7925 1050);
DISPLAY 0.872340 (-7925 1050);
PAINT AQUA (-7925 1050);
DISPLAY INVISIBLE (-7925 1050);
FORCEADD Q_CAP..1
(-1300 1425);
FORCEPROP 1 LAST LOCATION PC501_2
J 0
(-1250 1525);
DISPLAY 0.489362 (-1250 1525);
PAINT SKYBLUE (-1250 1525);
FORCEPROP 0 LAST $SEC 1
J 0
(-1250 1550);
DISPLAY 0.680851 (-1250 1550);
PAINT MONO (-1250 1550);
DISPLAY INVISIBLE (-1250 1550);
FORCEPROP 0 LAST CDS_SEC 1
J 0
(-1250 1550);
DISPLAY 1.021277 (-1250 1550);
DISPLAY INVISIBLE (-1250 1550);
FORCEPROP 1 LASTPIN (-1300 1525) $PN 1
J 0
(-1290 1505);
DISPLAY 0.489362 (-1290 1505);
PAINT MONO (-1290 1505);
FORCEPROP 1 LASTPIN (-1300 1325) $PN 2
J 0
(-1290 1305);
DISPLAY 0.489362 (-1290 1305);
PAINT MONO (-1290 1305);
FORCEPROP 1 LAST PACK_TYPE C0805
J 0
(-1250 1225);
DISPLAY 0.489362 (-1250 1225);
PAINT SKYBLUE (-1250 1225);
FORCEPROP 1 LAST MATERIAL X6S
J 0
(-1250 1325);
DISPLAY 0.489362 (-1250 1325);
PAINT SKYBLUE (-1250 1325);
FORCEPROP 1 LAST TOLERANCE 20%
J 0
(-1250 1375);
DISPLAY 0.489362 (-1250 1375);
PAINT SKYBLUE (-1250 1375);
FORCEPROP 1 LAST VALUE 22UF
J 0
(-1250 1475);
DISPLAY 0.489362 (-1250 1475);
PAINT SKYBLUE (-1250 1475);
FORCEPROP 1 LAST VOLTAGE 4V
J 0
(-1250 1425);
DISPLAY 0.489362 (-1250 1425);
PAINT SKYBLUE (-1250 1425);
FORCEPROP 2 LAST CDS_LIB pure_quanta
J 0
(-1300 1425);
DISPLAY INVISIBLE (-1300 1425);
FORCEPROP 1 LAST PATH I70
J 0
(-1250 1575);
DISPLAY 0.978723 (-1250 1575);
PAINT WHITE (-1250 1575);
DISPLAY INVISIBLE (-1250 1575);
FORCEPROP 1 LAST PART_NUMBER CH622KMEA03
J 0
(-1250 1275);
DISPLAY 0.489362 (-1250 1275);
PAINT SKYBLUE (-1250 1275);
DISPLAY INVISIBLE (-1250 1275);
FORCEADD VCC_CORE..1
(-1300 1750);
FORCEPROP 3 LASTPIN (-1300 1700) SIG_NAME PVDDCR_CPU0_P0\g
J 0
(-1290 1710);
DISPLAY 0.659574 (-1290 1710);
PAINT MONO (-1290 1710);
DISPLAY INVISIBLE (-1290 1710);
FORCEPROP 1 LAST HDL_POWER PVDDCR_CPU0_P0
J 1
(-1300 1800);
DISPLAY 0.489362 (-1300 1800);
PAINT GREEN (-1300 1800);
FORCEPROP 2 LAST CDS_LIB pure_quanta_power
J 0
(-1300 1750);
DISPLAY INVISIBLE (-1300 1750);
FORCEPROP 1 LAST PATH I71
J 0
(-1250 1775);
DISPLAY 0.872340 (-1250 1775);
PAINT AQUA (-1250 1775);
DISPLAY INVISIBLE (-1250 1775);
FORCEADD UNIVERSAL_GND..1
(-1875 2425);
FORCEPROP 3 LASTPIN (-1875 2475) SIG_NAME GND\g
J 0
(-1865 2485);
DISPLAY 0.659574 (-1865 2485);
PAINT MONO (-1865 2485);
DISPLAY INVISIBLE (-1865 2485);
FORCEPROP 2 LAST CDS_LIB pure_quanta_power
J 0
(-1875 2425);
DISPLAY INVISIBLE (-1875 2425);
FORCEPROP 1 LAST HDL_POWER GND
J 1
(-1850 2350);
DISPLAY 0.872340 (-1850 2350);
PAINT GREEN (-1850 2350);
DISPLAY INVISIBLE (-1850 2350);
FORCEPROP 1 LAST PATH I72
J 0
(-1800 2425);
DISPLAY 0.872340 (-1800 2425);
PAINT AQUA (-1800 2425);
DISPLAY INVISIBLE (-1800 2425);
FORCEADD Q_CAPP..1
(-1900 2800);
FORCEPROP 1 LAST LOCATION PC498
J 0
(-1850 2900);
DISPLAY 0.489362 (-1850 2900);
PAINT SKYBLUE (-1850 2900);
FORCEPROP 0 LAST $SEC 1
J 0
(-1850 2950);
DISPLAY 0.680851 (-1850 2950);
PAINT MONO (-1850 2950);
DISPLAY INVISIBLE (-1850 2950);
FORCEPROP 0 LAST CDS_SEC 1
J 0
(-1850 2950);
DISPLAY 1.021277 (-1850 2950);
DISPLAY INVISIBLE (-1850 2950);
FORCEPROP 1 LASTPIN (-1900 2900) $PN 1
J 0
(-1890 2885);
DISPLAY 0.489362 (-1890 2885);
PAINT MONO (-1890 2885);
FORCEPROP 1 LASTPIN (-1900 2700) $PN 2
J 0
(-1890 2685);
DISPLAY 0.489362 (-1890 2685);
PAINT MONO (-1890 2685);
FORCEPROP 1 LAST TOLERANCE 20%
J 0
(-1850 2800);
DISPLAY 0.489362 (-1850 2800);
PAINT SKYBLUE (-1850 2800);
FORCEPROP 1 LAST MATERIAL SPCAP
J 0
(-1850 2700);
DISPLAY 0.489362 (-1850 2700);
PAINT SKYBLUE (-1850 2700);
FORCEPROP 1 LAST PACK_TYPE SMLF
J 0
(-1850 2650);
DISPLAY 0.489362 (-1850 2650);
PAINT SKYBLUE (-1850 2650);
FORCEPROP 1 LAST VALUE 220UF
J 0
(-1850 2850);
DISPLAY 0.489362 (-1850 2850);
PAINT SKYBLUE (-1850 2850);
FORCEPROP 1 LAST VOLTAGE 4V
J 0
(-1850 2750);
DISPLAY 0.489362 (-1850 2750);
PAINT SKYBLUE (-1850 2750);
FORCEPROP 2 LAST CDS_LIB pure_quanta
J 0
(-1900 2800);
DISPLAY INVISIBLE (-1900 2800);
FORCEPROP 1 LAST PATH I73
J 0
(-1850 2950);
DISPLAY 0.978723 (-1850 2950);
DISPLAY INVISIBLE (-1850 2950);
FORCEPROP 1 LAST PART_NUMBER CH122KM8801
J 0
(-1850 2600);
DISPLAY 0.489362 (-1850 2600);
PAINT SKYBLUE (-1850 2600);
DISPLAY INVISIBLE (-1850 2600);
FORCEADD VCC_CORE..1
(-1875 3100);
FORCEPROP 3 LASTPIN (-1875 3050) SIG_NAME PVDDCR_CPU0_P0\g
J 0
(-1865 3060);
DISPLAY 0.659574 (-1865 3060);
PAINT MONO (-1865 3060);
DISPLAY INVISIBLE (-1865 3060);
FORCEPROP 1 LAST HDL_POWER PVDDCR_CPU0_P0
J 1
(-1875 3150);
DISPLAY 0.489362 (-1875 3150);
PAINT GREEN (-1875 3150);
FORCEPROP 2 LAST CDS_LIB pure_quanta_power
J 0
(-1875 3100);
DISPLAY INVISIBLE (-1875 3100);
FORCEPROP 1 LAST PATH I74
J 0
(-1825 3125);
DISPLAY 0.872340 (-1825 3125);
PAINT AQUA (-1825 3125);
DISPLAY INVISIBLE (-1825 3125);
FORCEADD UNIVERSAL_GND..1
(-775 3800);
FORCEPROP 3 LASTPIN (-775 3850) SIG_NAME GND\g
J 0
(-765 3860);
DISPLAY 0.659574 (-765 3860);
PAINT MONO (-765 3860);
DISPLAY INVISIBLE (-765 3860);
FORCEPROP 2 LAST CDS_LIB pure_quanta_power
J 0
(-775 3800);
DISPLAY INVISIBLE (-775 3800);
FORCEPROP 1 LAST HDL_POWER GND
J 1
(-750 3725);
DISPLAY 0.872340 (-750 3725);
PAINT GREEN (-750 3725);
DISPLAY INVISIBLE (-750 3725);
FORCEPROP 1 LAST PATH I75
J 0
(-700 3800);
DISPLAY 0.872340 (-700 3800);
PAINT AQUA (-700 3800);
DISPLAY INVISIBLE (-700 3800);
FORCEADD Q_CAP..1
(-4000 4575);
FORCEPROP 1 LAST LOCATION PC489
J 0
(-3950 4700);
DISPLAY 0.489362 (-3950 4700);
PAINT SKYBLUE (-3950 4700);
FORCEPROP 0 LAST $SEC 1
J 0
(-3950 4725);
DISPLAY 0.680851 (-3950 4725);
PAINT MONO (-3950 4725);
DISPLAY INVISIBLE (-3950 4725);
FORCEPROP 0 LAST CDS_SEC 1
J 0
(-3950 4725);
DISPLAY 1.021277 (-3950 4725);
DISPLAY INVISIBLE (-3950 4725);
FORCEPROP 1 LASTPIN (-4000 4675) $PN 1
J 0
(-3990 4655);
DISPLAY 0.489362 (-3990 4655);
PAINT MONO (-3990 4655);
FORCEPROP 1 LASTPIN (-4000 4475) $PN 2
J 0
(-3990 4455);
DISPLAY 0.489362 (-3990 4455);
PAINT MONO (-3990 4455);
FORCEPROP 1 LAST PACK_TYPE 0402
J 0
(-3950 4400);
DISPLAY 0.489362 (-3950 4400);
PAINT SKYBLUE (-3950 4400);
FORCEPROP 1 LAST MATERIAL X7R
J 0
(-3950 4500);
DISPLAY 0.489362 (-3950 4500);
PAINT SKYBLUE (-3950 4500);
FORCEPROP 1 LAST VOLTAGE 16V
J 0
(-3950 4600);
DISPLAY 0.489362 (-3950 4600);
PAINT SKYBLUE (-3950 4600);
FORCEPROP 1 LAST TOLERANCE 10%
J 0
(-3950 4550);
DISPLAY 0.489362 (-3950 4550);
PAINT SKYBLUE (-3950 4550);
FORCEPROP 1 LAST VALUE 0.22UF
J 0
(-3950 4650);
DISPLAY 0.489362 (-3950 4650);
PAINT SKYBLUE (-3950 4650);
FORCEPROP 2 LAST CDS_LIB pure_quanta
J 0
(-4000 4575);
DISPLAY INVISIBLE (-4000 4575);
FORCEPROP 1 LAST PATH I76
J 0
(-3950 4725);
DISPLAY 0.978723 (-3950 4725);
PAINT WHITE (-3950 4725);
DISPLAY INVISIBLE (-3950 4725);
FORCEPROP 1 LAST PART_NUMBER CH4223K1B00
J 0
(-3950 4450);
DISPLAY 0.489362 (-3950 4450);
PAINT SKYBLUE (-3950 4450);
DISPLAY INVISIBLE (-3950 4450);
FORCEADD Q_INDUCTOR4P_14..1
(-3250 4225);
FORCEPROP 1 LAST LOCATION PL51
J 0
(-3475 4480);
DISPLAY 0.489362 (-3475 4480);
PAINT SKYBLUE (-3475 4480);
FORCEPROP 0 LAST $SEC 1
J 0
(-3475 4625);
DISPLAY 0.680851 (-3475 4625);
PAINT MONO (-3475 4625);
DISPLAY INVISIBLE (-3475 4625);
FORCEPROP 0 LAST CDS_SEC 1
J 0
(-3475 4625);
DISPLAY 1.021277 (-3475 4625);
DISPLAY INVISIBLE (-3475 4625);
FORCEPROP 0 LASTPIN (-3650 4350) $PN 1
J 2
(-3660 4360);
DISPLAY 0.489362 (-3660 4360);
PAINT MONO (-3660 4360);
FORCEPROP 0 LASTPIN (-3650 4100) $PN 2
J 2
(-3660 4110);
DISPLAY 0.489362 (-3660 4110);
PAINT MONO (-3660 4110);
FORCEPROP 0 LASTPIN (-2850 4100) $PN 3
J 0
(-2840 4110);
DISPLAY 0.489362 (-2840 4110);
PAINT MONO (-2840 4110);
FORCEPROP 0 LASTPIN (-2850 4350) $PN 4
J 0
(-2840 4360);
DISPLAY 0.489362 (-2840 4360);
PAINT MONO (-2840 4360);
FORCEPROP 2 LAST PART_TYPE SMLF
J 0
(-3475 4575);
DISPLAY 1.021277 (-3475 4575);
FORCEPROP 2 LAST VALUE 150NH
J 0
(-3475 4525);
DISPLAY 0.489362 (-3475 4525);
PAINT SKYBLUE (-3475 4525);
FORCEPROP 1 LAST MATERIAL IND
J 0
(-3475 4435);
DISPLAY 0.489362 (-3475 4435);
PAINT SKYBLUE (-3475 4435);
FORCEPROP 2 LAST CDS_LIB pure_quanta
J 0
(-3250 4225);
DISPLAY INVISIBLE (-3250 4225);
FORCEPROP 1 LAST NEEDS_NO_SIZE TRUE
J 0
(-3250 4225);
DISPLAY 0.468085 (-3250 4225);
PAINT GREEN (-3250 4225);
DISPLAY INVISIBLE (-3250 4225);
FORCEPROP 1 LAST PATH I77
J 0
(-3050 4380);
DISPLAY 0.723404 (-3050 4380);
PAINT GREEN (-3050 4380);
DISPLAY INVISIBLE (-3050 4380);
FORCEPROP 1 LAST PART_NUMBER CV+15^0TZ04
J 0
(-3475 4385);
DISPLAY 0.489362 (-3475 4385);
PAINT SKYBLUE (-3475 4385);
DISPLAY INVISIBLE (-3475 4385);
FORCEADD UNIVERSAL_GND..1
(-4025 4900);
FORCEPROP 3 LASTPIN (-4025 4950) SIG_NAME GND\g
J 0
(-4015 4960);
DISPLAY 0.659574 (-4015 4960);
PAINT MONO (-4015 4960);
DISPLAY INVISIBLE (-4015 4960);
FORCEPROP 2 LAST CDS_LIB pure_quanta_power
J 0
(-4025 4900);
DISPLAY INVISIBLE (-4025 4900);
FORCEPROP 1 LAST HDL_POWER GND
J 1
(-4000 4825);
DISPLAY 0.872340 (-4000 4825);
PAINT GREEN (-4000 4825);
DISPLAY INVISIBLE (-4000 4825);
FORCEPROP 1 LAST PATH I78
J 0
(-3950 4900);
DISPLAY 0.872340 (-3950 4900);
PAINT AQUA (-3950 4900);
DISPLAY INVISIBLE (-3950 4900);
FORCEADD Q_CAPP..1
(-3950 5225);
FORCEPROP 1 LAST LOCATION PC491
J 0
(-3900 5325);
DISPLAY 0.489362 (-3900 5325);
PAINT SKYBLUE (-3900 5325);
FORCEPROP 0 LAST $SEC 1
J 0
(-3900 5350);
DISPLAY 0.680851 (-3900 5350);
PAINT MONO (-3900 5350);
DISPLAY INVISIBLE (-3900 5350);
FORCEPROP 0 LAST CDS_SEC 1
J 0
(-3900 5350);
DISPLAY 1.021277 (-3900 5350);
DISPLAY INVISIBLE (-3900 5350);
FORCEPROP 1 LASTPIN (-3950 5325) $PN 1
J 0
(-3940 5310);
DISPLAY 0.489362 (-3940 5310);
PAINT MONO (-3940 5310);
FORCEPROP 1 LASTPIN (-3950 5125) $PN 2
J 0
(-3940 5110);
DISPLAY 0.489362 (-3940 5110);
PAINT MONO (-3940 5110);
FORCEPROP 1 LAST VOLTAGE 16V
J 0
(-3900 5175);
DISPLAY 0.489362 (-3900 5175);
PAINT SKYBLUE (-3900 5175);
FORCEPROP 1 LAST MATERIAL OSCON
J 0
(-3900 5125);
DISPLAY 0.489362 (-3900 5125);
PAINT SKYBLUE (-3900 5125);
FORCEPROP 1 LAST PACK_TYPE THLF
J 0
(-3900 5075);
DISPLAY 0.489362 (-3900 5075);
PAINT SKYBLUE (-3900 5075);
FORCEPROP 1 LAST TOLERANCE 20%
J 0
(-3900 5225);
DISPLAY 0.489362 (-3900 5225);
PAINT SKYBLUE (-3900 5225);
FORCEPROP 1 LAST VALUE 270UF
J 0
(-3900 5275);
DISPLAY 0.489362 (-3900 5275);
PAINT SKYBLUE (-3900 5275);
FORCEPROP 2 LAST CDS_LIB pure_quanta
J 0
(-3950 5225);
DISPLAY INVISIBLE (-3950 5225);
FORCEPROP 1 LAST PATH I79
J 0
(-3900 5375);
DISPLAY 0.978723 (-3900 5375);
DISPLAY INVISIBLE (-3900 5375);
FORCEPROP 1 LAST PART_NUMBER CC72703MD38
J 0
(-3900 5025);
DISPLAY 0.489362 (-3900 5025);
PAINT SKYBLUE (-3900 5025);
DISPLAY INVISIBLE (-3900 5025);
FORCEADD Q_CAP..1
(-8000 1325);
FORCEPROP 1 LAST LOCATION PC474_2
J 0
(-7950 1425);
DISPLAY 0.489362 (-7950 1425);
PAINT SKYBLUE (-7950 1425);
FORCEPROP 0 LAST $SEC 1
J 0
(-7950 1450);
DISPLAY 0.680851 (-7950 1450);
PAINT MONO (-7950 1450);
DISPLAY INVISIBLE (-7950 1450);
FORCEPROP 0 LAST CDS_SEC 1
J 0
(-7950 1450);
DISPLAY 1.021277 (-7950 1450);
DISPLAY INVISIBLE (-7950 1450);
FORCEPROP 1 LASTPIN (-8000 1425) $PN 1
J 0
(-7990 1405);
DISPLAY 0.489362 (-7990 1405);
PAINT MONO (-7990 1405);
FORCEPROP 1 LASTPIN (-8000 1225) $PN 2
J 0
(-7990 1205);
DISPLAY 0.489362 (-7990 1205);
PAINT MONO (-7990 1205);
FORCEPROP 1 LAST PACK_TYPE 0402
J 0
(-7950 1125);
DISPLAY 0.489362 (-7950 1125);
PAINT SKYBLUE (-7950 1125);
FORCEPROP 1 LAST VOLTAGE 25V
J 0
(-7950 1325);
DISPLAY 0.489362 (-7950 1325);
PAINT SKYBLUE (-7950 1325);
FORCEPROP 1 LAST VALUE 0.1UF
J 0
(-7950 1375);
DISPLAY 0.489362 (-7950 1375);
PAINT SKYBLUE (-7950 1375);
FORCEPROP 1 LAST TOLERANCE 10%
J 0
(-7950 1275);
DISPLAY 0.489362 (-7950 1275);
PAINT SKYBLUE (-7950 1275);
FORCEPROP 1 LAST MATERIAL X7R
J 0
(-7950 1225);
DISPLAY 0.489362 (-7950 1225);
PAINT SKYBLUE (-7950 1225);
FORCEPROP 2 LAST CDS_LIB pure_quanta
J 0
(-8000 1325);
DISPLAY INVISIBLE (-8000 1325);
FORCEPROP 1 LAST PATH I8
J 0
(-7950 1475);
DISPLAY 0.978723 (-7950 1475);
PAINT WHITE (-7950 1475);
DISPLAY INVISIBLE (-7950 1475);
FORCEPROP 1 LAST PART_NUMBER CH4104K1B00
J 0
(-7950 1175);
DISPLAY 0.489362 (-7950 1175);
PAINT SKYBLUE (-7950 1175);
DISPLAY INVISIBLE (-7950 1175);
FORCEADD VCC_CORE..1
(-4025 5500);
FORCEPROP 3 LASTPIN (-4025 5450) SIG_NAME SW_P12V_AUX_PVDDCR_CPU0_P0_FLT\g
J 0
(-4015 5460);
DISPLAY 0.659574 (-4015 5460);
PAINT MONO (-4015 5460);
DISPLAY INVISIBLE (-4015 5460);
FORCEPROP 1 LAST HDL_POWER SW_P12V_AUX_PVDDCR_CPU0_P0_FLT
J 1
(-4025 5550);
DISPLAY 0.489362 (-4025 5550);
PAINT GREEN (-4025 5550);
FORCEPROP 2 LAST CDS_LIB pure_quanta_power
J 0
(-4025 5500);
DISPLAY INVISIBLE (-4025 5500);
FORCEPROP 1 LAST PATH I80
J 0
(-3975 5525);
DISPLAY 0.872340 (-3975 5525);
PAINT AQUA (-3975 5525);
DISPLAY INVISIBLE (-3975 5525);
FORCEADD Q_CAPP..1
(-3525 5225);
FORCEPROP 1 LAST LOCATION PC492
J 0
(-3475 5325);
DISPLAY 0.489362 (-3475 5325);
PAINT SKYBLUE (-3475 5325);
FORCEPROP 0 LAST $SEC 1
J 0
(-3475 5350);
DISPLAY 0.680851 (-3475 5350);
PAINT MONO (-3475 5350);
DISPLAY INVISIBLE (-3475 5350);
FORCEPROP 0 LAST CDS_SEC 1
J 0
(-3475 5350);
DISPLAY 1.021277 (-3475 5350);
DISPLAY INVISIBLE (-3475 5350);
FORCEPROP 1 LASTPIN (-3525 5325) $PN 1
J 0
(-3515 5310);
DISPLAY 0.489362 (-3515 5310);
PAINT MONO (-3515 5310);
FORCEPROP 1 LASTPIN (-3525 5125) $PN 2
J 0
(-3515 5110);
DISPLAY 0.489362 (-3515 5110);
PAINT MONO (-3515 5110);
FORCEPROP 1 LAST TOLERANCE 20%
J 0
(-3475 5225);
DISPLAY 0.489362 (-3475 5225);
PAINT SKYBLUE (-3475 5225);
FORCEPROP 1 LAST VALUE 270UF
J 0
(-3475 5275);
DISPLAY 0.489362 (-3475 5275);
PAINT SKYBLUE (-3475 5275);
FORCEPROP 1 LAST VOLTAGE 16V
J 0
(-3475 5175);
DISPLAY 0.489362 (-3475 5175);
PAINT SKYBLUE (-3475 5175);
FORCEPROP 1 LAST MATERIAL OSCON
J 0
(-3475 5125);
DISPLAY 0.489362 (-3475 5125);
PAINT SKYBLUE (-3475 5125);
FORCEPROP 1 LAST PACK_TYPE THLF
J 0
(-3475 5075);
DISPLAY 0.489362 (-3475 5075);
PAINT SKYBLUE (-3475 5075);
FORCEPROP 2 LAST CDS_LIB pure_quanta
J 0
(-3525 5225);
DISPLAY INVISIBLE (-3525 5225);
FORCEPROP 1 LAST PATH I81
J 0
(-3475 5375);
DISPLAY 0.978723 (-3475 5375);
DISPLAY INVISIBLE (-3475 5375);
FORCEPROP 1 LAST PART_NUMBER CC72703MD38
J 0
(-3475 5025);
DISPLAY 0.489362 (-3475 5025);
PAINT SKYBLUE (-3475 5025);
DISPLAY INVISIBLE (-3475 5025);
FORCEADD Q_INDUCTOR..1
(-3075 5425);
FORCEPROP 1 LAST LOCATION PL53
J 0
(-3200 5585);
DISPLAY 0.489362 (-3200 5585);
PAINT SKYBLUE (-3200 5585);
FORCEPROP 0 LAST $SEC 1
J 0
(-3200 5700);
DISPLAY 0.680851 (-3200 5700);
PAINT MONO (-3200 5700);
DISPLAY INVISIBLE (-3200 5700);
FORCEPROP 0 LAST CDS_SEC 1
J 0
(-3200 5700);
DISPLAY 1.021277 (-3200 5700);
DISPLAY INVISIBLE (-3200 5700);
FORCEPROP 0 LASTPIN (-3175 5400) $PN 1
J 2
(-3185 5410);
DISPLAY 0.489362 (-3185 5410);
PAINT MONO (-3185 5410);
FORCEPROP 0 LASTPIN (-2975 5400) $PN 2
J 0
(-2965 5410);
DISPLAY 0.489362 (-2965 5410);
PAINT MONO (-2965 5410);
FORCEPROP 2 LAST VALUE 50NH/86A
J 0
(-3200 5675);
DISPLAY 0.489362 (-3200 5675);
PAINT SKYBLUE (-3200 5675);
FORCEPROP 2 LAST PACK_TYPE SMLF
J 0
(-3200 5625);
DISPLAY 0.489362 (-3200 5625);
PAINT SKYBLUE (-3200 5625);
FORCEPROP 1 LAST MATERIAL IND
J 0
(-3200 5480);
DISPLAY 0.489362 (-3200 5480);
PAINT SKYBLUE (-3200 5480);
FORCEPROP 2 LAST CDS_LIB pure_quanta
J 0
(-3075 5425);
DISPLAY INVISIBLE (-3075 5425);
FORCEPROP 1 LAST NEEDS_NO_SIZE TRUE
J 0
(-3075 5425);
DISPLAY 0.468085 (-3075 5425);
PAINT GREEN (-3075 5425);
DISPLAY INVISIBLE (-3075 5425);
FORCEPROP 1 LAST PATH I82
J 0
(-3000 5480);
DISPLAY 0.723404 (-3000 5480);
PAINT GREEN (-3000 5480);
DISPLAY INVISIBLE (-3000 5480);
FORCEPROP 1 LAST PART_NUMBER CVA50^0MZ09
J 0
(-3200 5535);
DISPLAY 0.489362 (-3200 5535);
PAINT SKYBLUE (-3200 5535);
DISPLAY INVISIBLE (-3200 5535);
FORCEADD UNIVERSAL_GND..1
(-2700 4950);
FORCEPROP 3 LASTPIN (-2700 5000) SIG_NAME GND\g
J 0
(-2690 5010);
DISPLAY 0.659574 (-2690 5010);
PAINT MONO (-2690 5010);
DISPLAY INVISIBLE (-2690 5010);
FORCEPROP 2 LAST CDS_LIB pure_quanta_power
J 0
(-2700 4950);
DISPLAY INVISIBLE (-2700 4950);
FORCEPROP 1 LAST HDL_POWER GND
J 1
(-2675 4875);
DISPLAY 0.872340 (-2675 4875);
PAINT GREEN (-2675 4875);
DISPLAY INVISIBLE (-2675 4875);
FORCEPROP 1 LAST PATH I83
J 0
(-2625 4950);
DISPLAY 0.872340 (-2625 4950);
PAINT AQUA (-2625 4950);
DISPLAY INVISIBLE (-2625 4950);
FORCEADD OFFPAGE..3
(-2325 4100);
FORCEPROP 2 LAST $XR0 194 
J 0
(-2111 4100);
DISPLAY 0.638298 (-2111 4100);
PAINT MONO (-2111 4100);
FORCEPROP 2 LAST CDS_LIB standard
J 2
(-2325 4100);
DISPLAY INVISIBLE (-2325 4100);
FORCEPROP 1 LAST OFFPAGE TRUE
J 0
(-2000 3975);
DISPLAY 0.872340 (-2000 3975);
PAINT GREEN (-2000 3975);
DISPLAY INVISIBLE (-2000 3975);
FORCEPROP 1 LAST COMMENT_BODY TRUE
J 0
(-2375 4000);
DISPLAY 0.872340 (-2375 4000);
PAINT GREEN (-2375 4000);
DISPLAY INVISIBLE (-2375 4000);
FORCEPROP 2 LAST PATH I84
J 0
(-2100 4150);
DISPLAY 0.680851 (-2100 4150);
DISPLAY INVISIBLE (-2100 4150);
FORCEADD Q_CAP..1
(-2700 5250);
FORCEPROP 1 LAST LOCATION PC479
J 0
(-2650 5350);
DISPLAY 0.489362 (-2650 5350);
PAINT SKYBLUE (-2650 5350);
FORCEPROP 0 LAST $SEC 1
J 0
(-2650 5375);
DISPLAY 0.680851 (-2650 5375);
PAINT MONO (-2650 5375);
DISPLAY INVISIBLE (-2650 5375);
FORCEPROP 0 LAST CDS_SEC 1
J 0
(-2650 5375);
DISPLAY 0.680851 (-2650 5375);
DISPLAY INVISIBLE (-2650 5375);
FORCEPROP 1 LASTPIN (-2700 5350) $PN 1
J 0
(-2690 5330);
DISPLAY 0.787234 (-2690 5330);
PAINT MONO (-2690 5330);
FORCEPROP 1 LASTPIN (-2700 5150) $PN 2
J 0
(-2690 5130);
DISPLAY 0.787234 (-2690 5130);
PAINT MONO (-2690 5130);
FORCEPROP 1 LAST TOLERANCE 10%
J 0
(-2650 5200);
DISPLAY 0.489362 (-2650 5200);
PAINT SKYBLUE (-2650 5200);
FORCEPROP 1 LAST PACK_TYPE 0402
J 0
(-2650 5050);
DISPLAY 0.489362 (-2650 5050);
PAINT SKYBLUE (-2650 5050);
FORCEPROP 1 LAST MATERIAL X7R
J 0
(-2650 5150);
DISPLAY 0.489362 (-2650 5150);
PAINT SKYBLUE (-2650 5150);
FORCEPROP 1 LAST VOLTAGE 25V
J 0
(-2650 5250);
DISPLAY 0.489362 (-2650 5250);
PAINT SKYBLUE (-2650 5250);
FORCEPROP 1 LAST VALUE 0.1UF
J 0
(-2650 5300);
DISPLAY 0.489362 (-2650 5300);
PAINT SKYBLUE (-2650 5300);
FORCEPROP 2 LAST CDS_LIB pure_quanta
J 0
(-2700 5250);
DISPLAY INVISIBLE (-2700 5250);
FORCEPROP 1 LAST PATH I85
J 0
(-2650 5400);
DISPLAY 0.978723 (-2650 5400);
PAINT WHITE (-2650 5400);
DISPLAY INVISIBLE (-2650 5400);
FORCEPROP 1 LAST PART_NUMBER CH4104K1B00
J 0
(-2650 5100);
DISPLAY 0.489362 (-2650 5100);
PAINT SKYBLUE (-2650 5100);
DISPLAY INVISIBLE (-2650 5100);
FORCEADD VCC_CORE..1
(-2700 5500);
FORCEPROP 3 LASTPIN (-2700 5450) SIG_NAME P12V_AUX\g
J 0
(-2690 5460);
DISPLAY 0.659574 (-2690 5460);
PAINT MONO (-2690 5460);
DISPLAY INVISIBLE (-2690 5460);
FORCEPROP 1 LAST HDL_POWER P12V_AUX
J 1
(-2700 5550);
DISPLAY 0.489362 (-2700 5550);
PAINT GREEN (-2700 5550);
FORCEPROP 2 LAST CDS_LIB pure_quanta_power
J 0
(-2700 5500);
DISPLAY INVISIBLE (-2700 5500);
FORCEPROP 1 LAST PATH I86
J 0
(-2650 5525);
DISPLAY 0.872340 (-2650 5525);
PAINT AQUA (-2650 5525);
DISPLAY INVISIBLE (-2650 5525);
FORCEADD Q_CAP..1
(-2000 4175);
FORCEPROP 1 LAST LOCATION PC497
J 0
(-1950 4275);
DISPLAY 0.489362 (-1950 4275);
PAINT SKYBLUE (-1950 4275);
FORCEPROP 0 LAST $SEC 1
J 0
(-1950 4300);
DISPLAY 0.680851 (-1950 4300);
PAINT MONO (-1950 4300);
DISPLAY INVISIBLE (-1950 4300);
FORCEPROP 0 LAST CDS_SEC 1
J 0
(-1950 4300);
DISPLAY 1.021277 (-1950 4300);
DISPLAY INVISIBLE (-1950 4300);
FORCEPROP 1 LASTPIN (-2000 4275) $PN 1
J 0
(-1990 4255);
DISPLAY 0.489362 (-1990 4255);
PAINT MONO (-1990 4255);
FORCEPROP 1 LASTPIN (-2000 4075) $PN 2
J 0
(-1990 4055);
DISPLAY 0.489362 (-1990 4055);
PAINT MONO (-1990 4055);
FORCEPROP 1 LAST TOLERANCE 10%
J 0
(-1950 4125);
DISPLAY 0.489362 (-1950 4125);
PAINT SKYBLUE (-1950 4125);
FORCEPROP 1 LAST MATERIAL X7R
J 0
(-1950 4075);
DISPLAY 0.489362 (-1950 4075);
PAINT SKYBLUE (-1950 4075);
FORCEPROP 1 LAST PACK_TYPE 0402
J 0
(-1950 3975);
DISPLAY 0.489362 (-1950 3975);
PAINT SKYBLUE (-1950 3975);
FORCEPROP 1 LAST VOLTAGE 25V
J 0
(-1950 4175);
DISPLAY 0.489362 (-1950 4175);
PAINT SKYBLUE (-1950 4175);
FORCEPROP 1 LAST VALUE 0.1UF
J 0
(-1950 4225);
DISPLAY 0.489362 (-1950 4225);
PAINT SKYBLUE (-1950 4225);
FORCEPROP 2 LAST CDS_LIB pure_quanta
J 0
(-2000 4175);
DISPLAY INVISIBLE (-2000 4175);
FORCEPROP 1 LAST PATH I87
J 0
(-1950 4325);
DISPLAY 0.978723 (-1950 4325);
PAINT WHITE (-1950 4325);
DISPLAY INVISIBLE (-1950 4325);
FORCEPROP 1 LAST PART_NUMBER CH4104K1B00
J 0
(-1950 4025);
DISPLAY 0.489362 (-1950 4025);
PAINT SKYBLUE (-1950 4025);
DISPLAY INVISIBLE (-1950 4025);
FORCEADD Q_CAP..1
(-1625 4175);
FORCEPROP 1 LAST LOCATION PC500_1
J 0
(-1575 4275);
DISPLAY 0.489362 (-1575 4275);
PAINT SKYBLUE (-1575 4275);
FORCEPROP 0 LAST $SEC 1
J 0
(-1575 4300);
DISPLAY 0.680851 (-1575 4300);
PAINT MONO (-1575 4300);
DISPLAY INVISIBLE (-1575 4300);
FORCEPROP 0 LAST CDS_SEC 1
J 0
(-1575 4300);
DISPLAY 1.021277 (-1575 4300);
DISPLAY INVISIBLE (-1575 4300);
FORCEPROP 1 LASTPIN (-1625 4275) $PN 1
J 0
(-1615 4255);
DISPLAY 0.489362 (-1615 4255);
PAINT MONO (-1615 4255);
FORCEPROP 1 LASTPIN (-1625 4075) $PN 2
J 0
(-1615 4055);
DISPLAY 0.489362 (-1615 4055);
PAINT MONO (-1615 4055);
FORCEPROP 1 LAST TOLERANCE 20%
J 0
(-1575 4125);
DISPLAY 0.489362 (-1575 4125);
PAINT SKYBLUE (-1575 4125);
FORCEPROP 1 LAST PACK_TYPE C0805
J 0
(-1575 3975);
DISPLAY 0.489362 (-1575 3975);
PAINT SKYBLUE (-1575 3975);
FORCEPROP 1 LAST MATERIAL X6S
J 0
(-1575 4075);
DISPLAY 0.489362 (-1575 4075);
PAINT SKYBLUE (-1575 4075);
FORCEPROP 1 LAST VALUE 22UF
J 0
(-1575 4225);
DISPLAY 0.489362 (-1575 4225);
PAINT SKYBLUE (-1575 4225);
FORCEPROP 1 LAST VOLTAGE 4V
J 0
(-1575 4175);
DISPLAY 0.489362 (-1575 4175);
PAINT SKYBLUE (-1575 4175);
FORCEPROP 2 LAST CDS_LIB pure_quanta
J 0
(-1625 4175);
DISPLAY INVISIBLE (-1625 4175);
FORCEPROP 1 LAST PATH I88
J 0
(-1575 4325);
DISPLAY 0.978723 (-1575 4325);
PAINT WHITE (-1575 4325);
DISPLAY INVISIBLE (-1575 4325);
FORCEPROP 1 LAST PART_NUMBER CH622KMEA03
J 0
(-1575 4025);
DISPLAY 0.489362 (-1575 4025);
PAINT SKYBLUE (-1575 4025);
DISPLAY INVISIBLE (-1575 4025);
FORCEADD Q_CAP..1
(-1175 4175);
FORCEPROP 1 LAST LOCATION PC502_1
J 0
(-1125 4275);
DISPLAY 0.489362 (-1125 4275);
PAINT SKYBLUE (-1125 4275);
FORCEPROP 0 LAST $SEC 1
J 0
(-1125 4300);
DISPLAY 0.680851 (-1125 4300);
PAINT MONO (-1125 4300);
DISPLAY INVISIBLE (-1125 4300);
FORCEPROP 0 LAST CDS_SEC 1
J 0
(-1125 4300);
DISPLAY 1.021277 (-1125 4300);
DISPLAY INVISIBLE (-1125 4300);
FORCEPROP 1 LASTPIN (-1175 4275) $PN 1
J 0
(-1165 4255);
DISPLAY 0.489362 (-1165 4255);
PAINT MONO (-1165 4255);
FORCEPROP 1 LASTPIN (-1175 4075) $PN 2
J 0
(-1165 4055);
DISPLAY 0.489362 (-1165 4055);
PAINT MONO (-1165 4055);
FORCEPROP 1 LAST VOLTAGE 4V
J 0
(-1125 4175);
DISPLAY 0.489362 (-1125 4175);
PAINT SKYBLUE (-1125 4175);
FORCEPROP 1 LAST PACK_TYPE C0805
J 0
(-1125 4025);
DISPLAY 0.489362 (-1125 4025);
PAINT SKYBLUE (-1125 4025);
FORCEPROP 1 LAST MATERIAL X6S
J 0
(-1125 4075);
DISPLAY 0.489362 (-1125 4075);
PAINT SKYBLUE (-1125 4075);
FORCEPROP 1 LAST TOLERANCE 20%
J 0
(-1125 4125);
DISPLAY 0.489362 (-1125 4125);
PAINT SKYBLUE (-1125 4125);
FORCEPROP 1 LAST VALUE 22UF
J 0
(-1125 4225);
DISPLAY 0.489362 (-1125 4225);
PAINT SKYBLUE (-1125 4225);
FORCEPROP 2 LAST CDS_LIB pure_quanta
J 0
(-1175 4175);
DISPLAY INVISIBLE (-1175 4175);
FORCEPROP 1 LAST PATH I89
J 0
(-1125 4325);
DISPLAY 0.978723 (-1125 4325);
PAINT WHITE (-1125 4325);
DISPLAY INVISIBLE (-1125 4325);
FORCEPROP 1 LAST PART_NUMBER CH622KMEA03
J 0
(-1125 4025);
DISPLAY 0.489362 (-1125 4025);
PAINT SKYBLUE (-1125 4025);
DISPLAY INVISIBLE (-1125 4025);
FORCEADD UNIVERSAL_GND..1
(-7675 1125);
FORCEPROP 3 LASTPIN (-7675 1175) SIG_NAME GND\g
J 0
(-7665 1185);
DISPLAY 0.659574 (-7665 1185);
PAINT MONO (-7665 1185);
DISPLAY INVISIBLE (-7665 1185);
FORCEPROP 2 LAST CDS_LIB pure_quanta_power
J 0
(-7675 1125);
DISPLAY INVISIBLE (-7675 1125);
FORCEPROP 1 LAST HDL_POWER GND
J 1
(-7650 1050);
DISPLAY 0.872340 (-7650 1050);
PAINT GREEN (-7650 1050);
DISPLAY INVISIBLE (-7650 1050);
FORCEPROP 1 LAST PATH I9
J 0
(-7600 1125);
DISPLAY 0.872340 (-7600 1125);
PAINT AQUA (-7600 1125);
DISPLAY INVISIBLE (-7600 1125);
FORCEADD Q_RES..2
(-775 4150);
FORCEPROP 1 LAST LOCATION PR447
J 0
(-730 4275);
DISPLAY 0.489362 (-730 4275);
PAINT SKYBLUE (-730 4275);
FORCEPROP 0 LAST $SEC 1
J 0
(-725 4300);
DISPLAY 0.680851 (-725 4300);
PAINT MONO (-725 4300);
DISPLAY INVISIBLE (-725 4300);
FORCEPROP 0 LAST CDS_SEC 1
J 0
(-725 4300);
DISPLAY 1.021277 (-725 4300);
DISPLAY INVISIBLE (-725 4300);
FORCEPROP 1 LASTPIN (-775 4250) $PN 1
J 0
(-770 4212);
DISPLAY 0.787234 (-770 4212);
PAINT MONO (-770 4212);
DISPLAY INVISIBLE (-770 4212);
FORCEPROP 1 LASTPIN (-775 4050) $PN 2
J 0
(-770 4060);
DISPLAY 0.787234 (-770 4060);
PAINT MONO (-770 4060);
DISPLAY INVISIBLE (-770 4060);
FORCEPROP 1 LAST WATTAGE 1/16W
J 0
(-735 4125);
DISPLAY 0.489362 (-735 4125);
PAINT SKYBLUE (-735 4125);
FORCEPROP 1 LAST MATERIAL CHIP
J 0
(-735 4075);
DISPLAY 0.489362 (-735 4075);
PAINT SKYBLUE (-735 4075);
FORCEPROP 1 LAST TOLERANCE 1%
J 0
(-730 4175);
DISPLAY 0.489362 (-730 4175);
PAINT SKYBLUE (-730 4175);
FORCEPROP 1 LAST VALUE 1K
J 0
(-730 4225);
DISPLAY 0.489362 (-730 4225);
PAINT SKYBLUE (-730 4225);
FORCEPROP 1 LAST PACK_TYPE 0402LF
J 0
(-735 3975);
DISPLAY 0.489362 (-735 3975);
PAINT SKYBLUE (-735 3975);
FORCEPROP 2 LAST CDS_LIB pure_quanta
J 0
(-775 4150);
DISPLAY INVISIBLE (-775 4150);
FORCEPROP 1 LAST PATH I90
J 0
(-725 4325);
DISPLAY 0.978723 (-725 4325);
PAINT WHITE (-725 4325);
DISPLAY INVISIBLE (-725 4325);
FORCEPROP 1 LAST PART_NUMBER CS21002FB06
J 0
(-735 4025);
DISPLAY 0.489362 (-735 4025);
PAINT SKYBLUE (-735 4025);
DISPLAY INVISIBLE (-735 4025);
FORCEADD VCC_CORE..1
(-775 4525);
FORCEPROP 3 LASTPIN (-775 4475) SIG_NAME PVDDCR_CPU0_P0\g
J 0
(-765 4485);
DISPLAY 0.659574 (-765 4485);
PAINT MONO (-765 4485);
DISPLAY INVISIBLE (-765 4485);
FORCEPROP 1 LAST HDL_POWER PVDDCR_CPU0_P0
J 1
(-775 4575);
DISPLAY 0.489362 (-775 4575);
PAINT GREEN (-775 4575);
FORCEPROP 2 LAST CDS_LIB pure_quanta_power
J 0
(-775 4525);
DISPLAY INVISIBLE (-775 4525);
FORCEPROP 1 LAST PATH I91
J 0
(-725 4550);
DISPLAY 0.872340 (-725 4550);
PAINT AQUA (-725 4550);
DISPLAY INVISIBLE (-725 4550);
FORCEADD DNS..1
(-8275 5675);
PAINT RED (-8275 5675);
FORCEPROP 2 LAST CDS_LIB mstr_misc
J 0
(-8275 5675);
DISPLAY INVISIBLE (-8275 5675);
FORCEPROP 1 LAST COMMENT_BODY TRUE
R 1
J 0
(-8200 5450);
DISPLAY 0.872340 (-8200 5450);
PAINT GREEN (-8200 5450);
DISPLAY INVISIBLE (-8200 5450);
FORCEADD DNS..1
(-7350 1275);
PAINT RED (-7350 1275);
FORCEPROP 2 LAST CDS_LIB mstr_misc
J 0
(-7350 1275);
DISPLAY INVISIBLE (-7350 1275);
FORCEPROP 1 LAST COMMENT_BODY TRUE
R 1
J 0
(-7275 1050);
DISPLAY 0.872340 (-7275 1050);
PAINT GREEN (-7275 1050);
DISPLAY INVISIBLE (-7275 1050);
FORCEADD DNS..1
(-7350 4025);
PAINT RED (-7350 4025);
FORCEPROP 2 LAST CDS_LIB mstr_misc
J 0
(-7350 4025);
DISPLAY INVISIBLE (-7350 4025);
FORCEPROP 1 LAST COMMENT_BODY TRUE
R 1
J 0
(-7275 3800);
DISPLAY 0.872340 (-7275 3800);
PAINT GREEN (-7275 3800);
DISPLAY INVISIBLE (-7275 3800);
FORCEADD DNS..1
(-4675 975);
PAINT RED (-4675 975);
FORCEPROP 2 LAST CDS_LIB mstr_misc
J 0
(-4675 975);
DISPLAY INVISIBLE (-4675 975);
FORCEPROP 1 LAST COMMENT_BODY TRUE
R 1
J 0
(-4600 750);
DISPLAY 0.872340 (-4600 750);
PAINT GREEN (-4600 750);
DISPLAY INVISIBLE (-4600 750);
FORCEADD DNS..1
(-4675 1425);
PAINT RED (-4675 1425);
FORCEPROP 2 LAST CDS_LIB mstr_misc
J 0
(-4675 1425);
DISPLAY INVISIBLE (-4675 1425);
FORCEPROP 1 LAST COMMENT_BODY TRUE
R 1
J 0
(-4600 1200);
DISPLAY 0.872340 (-4600 1200);
PAINT GREEN (-4600 1200);
DISPLAY INVISIBLE (-4600 1200);
FORCEADD DNS..1
(-4850 3725);
PAINT RED (-4850 3725);
FORCEPROP 2 LAST CDS_LIB mstr_misc
J 0
(-4850 3725);
DISPLAY INVISIBLE (-4850 3725);
FORCEPROP 1 LAST COMMENT_BODY TRUE
R 1
J 0
(-4775 3500);
DISPLAY 0.872340 (-4775 3500);
PAINT GREEN (-4775 3500);
DISPLAY INVISIBLE (-4775 3500);
FORCEADD DNS..1
(-4850 4175);
PAINT RED (-4850 4175);
FORCEPROP 2 LAST CDS_LIB mstr_misc
J 0
(-4850 4175);
DISPLAY INVISIBLE (-4850 4175);
FORCEPROP 1 LAST COMMENT_BODY TRUE
R 1
J 0
(-4775 3950);
DISPLAY 0.872340 (-4775 3950);
PAINT GREEN (-4775 3950);
DISPLAY INVISIBLE (-4775 3950);
FORCEADD QUANTA_TITLE_BLOCK_C..1
(0 0);
FORCEPROP 0 LAST CDS_CON_LAST_MODIFIED Thu Sep 14 16:12:17 2023
J 0
(-1885 15);
DISPLAY INVISIBLE (-1885 15);
FORCEPROP 1 LAST CUSTOM_TXT_CDS <CON_LAST_MODIFIED>
J 0
(-1885 15);
DISPLAY 0.978723 (-1885 15);
FORCEPROP 2 LAST CUSTOM_TXT_CDS <XR_PAGE_TITLE>
J 0
(-7890 5250);
DISPLAY 0.638298 (-7890 5250);
PAINT PINK (-7890 5250);
DISPLAY INVISIBLE (-7890 5250);
FORCEPROP 1 LAST CUSTOM_TXT_CDS <NAME_2>
J 0
(-3175 50);
FORCEPROP 1 LAST CUSTOM_TXT_CDS <NAME_1>
J 0
(-3175 175);
FORCEPROP 1 LAST CUSTOM_TXT_CDS <Q_NUMBER>
J 0
(-1403 103);
DISPLAY 1.212766 (-1403 103);
FORCEPROP 1 LAST CUSTOM_TXT_CDS <Q_PROJ>
J 0
(-2382 102);
DISPLAY 1.212766 (-2382 102);
FORCEPROP 1 LAST CUSTOM_TXT_CDS <Q_REV>
J 0
(-184 103);
DISPLAY 1.212766 (-184 103);
FORCEPROP 1 LAST CUSTOM_TXT_CDS <CON_PAGE_NUM> OF <CON_TOTAL_PAGES>
J 0
(-446 18);
DISPLAY 0.978723 (-446 18);
FORCEPROP 1 LAST Q_TITLE PVDDCR_CPU0_P0 VR PHASE 1&2
J 0
(-9325 50);
DISPLAY 2.446809 (-9325 50);
PAINT GREEN (-9325 50);
FORCEPROP 2 LAST CDS_LIB pure_quanta
J 0
(0 0);
DISPLAY INVISIBLE (0 0);
FORCEPROP 1 LAST CDS_LMAN_SYM_OUTLINE -9475,6775,100,-125
J 0
(0 0);
DISPLAY 0.468085 (0 0);
PAINT GREEN (0 0);
DISPLAY INVISIBLE (0 0);
FORCEPROP 2 LAST PAGE_BORDER TRUE
J 0
(-7890 5250);
DISPLAY 0.638298 (-7890 5250);
PAINT PINK (-7890 5250);
DISPLAY INVISIBLE (-7890 5250);
FORCEPROP 2 LAST CDS_XR_PAGE_TITLE CR-194 : @T6G_MB_LIB.T6G(SCH_1):PAGE194
J 0
(-7890 5250);
DISPLAY 0.638298 (-7890 5250);
PAINT PINK (-7890 5250);
DISPLAY INVISIBLE (-7890 5250);
FORCEPROP 1 LAST Q_DEPT BU9
J 1
(-3763 49);
DISPLAY 1.957447 (-3763 49);
PAINT GREEN (-3763 49);
DISPLAY INVISIBLE (-3763 49);
FORCEPROP 1 LAST COMMENT_BODY TRUE
J 0
(12 -13);
DISPLAY 0.978723 (12 -13);
PAINT GREEN (12 -13);
DISPLAY INVISIBLE (12 -13);
WIRE 16 -1 (-7650 1850)(-7650 1800);
WIRE 16 -1 (-7300 2375)(-7300 2250);
WIRE 16 -1 (-8025 3975)(-8025 3850);
WIRE 16 -1 (-7450 4050)(-7675 4050);
WIRE 16 -1 (-7675 4050)(-7675 3925);
WIRE 16 -1 (-4650 875)(-4650 800);
WIRE 16 -1 (-4825 3625)(-4825 3550);
WIRE 16 -1 (-7975 4600)(-7975 4550);
WIRE 16 -1 (-7625 5100)(-7625 5000);
WIRE 16 -1 (-8625 5775)(-8625 5725);
WIRE 16 -1 (-8275 5775)(-8275 5725);
WIRE 16 -1 (-8000 1225)(-8000 1100);
WIRE 16 -1 (-2700 5150)(-2700 5000);
WIRE 16 -1 (-7450 1300)(-7675 1300);
WIRE 16 -1 (-7675 1300)(-7675 1175);
WIRE 16 -1 (-5550 5000)(-5550 5125);
WIRE 16 -1 (-5550 5000)(-5225 5000);
WIRE 16 -1 (-5225 5000)(-4900 5000);
WIRE 16 -1 (-5225 5125)(-5225 5000);
WIRE 16 -1 (-4900 5125)(-4900 5000);
WIRE 16 -1 (-4900 5000)(-4575 5000);
WIRE 16 -1 (-4575 5125)(-4575 5000);
WIRE 16 -1 (-4275 5000)(-4575 5000);
WIRE 16 -1 (-4275 5000)(-4025 5000);
WIRE 16 -1 (-4275 5125)(-4275 5000);
WIRE 16 -1 (-4025 5000)(-3950 5000);
WIRE 16 -1 (-4025 5000)(-4025 4950);
WIRE 16 -1 (-3525 5000)(-3950 5000);
WIRE 16 -1 (-3950 5125)(-3950 5000);
WIRE 16 -1 (-3525 5125)(-3525 5000);
WIRE 16 -1 (-8625 5525)(-8625 5450);
WIRE 16 -1 (-8625 5450)(-8275 5450);
WIRE 16 -1 (-7975 5450)(-8275 5450);
WIRE 16 -1 (-8275 5525)(-8275 5450);
WIRE 16 -1 (-7800 5450)(-7975 5450);
WIRE 16 -1 (-7975 5300)(-7975 5450);
WIRE 16 -1 (-7800 5450)(-7625 5450);
WIRE 16 -1 (-7800 5775)(-7800 5450);
WIRE 16 -1 (-7000 5450)(-7625 5450);
WIRE 16 -1 (-7625 5300)(-7625 5450);
WIRE 16 -1 (-7000 5000)(-7000 5450);
WIRE 16 -1 (-7000 5000)(-6650 5000);
WIRE 16 -1 (-7225 4875)(-7225 4700);
FORCEPROP 2 LAST SIG_NAME PVDDCR_CPU0_P0_VCC1
J 2
(-6760 4710);
DISPLAY 0.489362 (-6760 4710);
FORCEPROP 2 LASTPROP $XRERR UNIQUE?
J 0
(-7000 4710);
DISPLAY 0.638298 (-7000 4710);
PAINT MONO (-7000 4710);
DISPLAY INVISIBLE (-7000 4710);
WIRE 16 -1 (-7225 4875)(-7975 4875);
WIRE 16 -1 (-7225 4700)(-6650 4700);
WIRE 16 -1 (-7225 4700)(-7225 4500);
WIRE 16 -1 (-7225 4500)(-6650 4500);
WIRE 16 -1 (-7975 5100)(-7975 4875);
WIRE 16 -1 (-7975 4875)(-7975 4800);
WIRE 16 -1 (-4575 2375)(-4575 2250);
WIRE 16 -1 (-4275 2250)(-4575 2250);
WIRE 16 -1 (-4900 2250)(-4575 2250);
WIRE 16 -1 (-4900 2375)(-4900 2250);
WIRE 16 -1 (-5225 2250)(-4900 2250);
WIRE 16 -1 (-4275 2375)(-4275 2250);
WIRE 16 -1 (-4275 2250)(-4275 2175);
WIRE 16 -1 (-5225 2375)(-5225 2250);
WIRE 16 -1 (-5550 2250)(-5225 2250);
WIRE 16 -1 (-5550 2375)(-5550 2250);
WIRE 16 -1 (-5675 2650)(-5675 2250);
WIRE 16 -1 (-5675 2650)(-5550 2650);
WIRE 16 -1 (-5675 2250)(-5675 2200);
WIRE 16 -1 (-5775 2250)(-5675 2250);
WIRE 16 -1 (-5675 2200)(-5775 2200);
WIRE 16 -1 (-5550 2650)(-5225 2650);
WIRE 16 -1 (-5550 2575)(-5550 2650);
WIRE 16 -1 (-5225 2650)(-4900 2650);
WIRE 16 -1 (-5225 2575)(-5225 2650);
WIRE 16 -1 (-4900 2650)(-4575 2650);
WIRE 16 -1 (-4900 2575)(-4900 2650);
WIRE 16 -1 (-4575 2650)(-4275 2650);
WIRE 16 -1 (-4575 2650)(-4575 2575);
WIRE 16 -1 (-4275 2725)(-4275 2650);
WIRE 16 -1 (-4275 2650)(-4275 2575);
WIRE 16 -1 (-5800 4100)(-5050 4100);
WIRE 16 -1 (-5050 3400)(-5050 4100);
WIRE 16 -1 (-4475 3400)(-5050 3400);
FORCEPROP 2 LAST SIG_NAME PVDDCR_CPU0_P0_VOS1
J 0
(-5685 4125);
DISPLAY 0.489362 (-5685 4125);
FORCEPROP 2 LASTPROP $XRERR UNIQUE?
J 0
(-5925 4125);
DISPLAY 0.638298 (-5925 4125);
PAINT MONO (-5925 4125);
DISPLAY INVISIBLE (-5925 4125);
WIRE 16 -1 (-4000 4475)(-4000 4450);
WIRE 16 -1 (-4000 4450)(-5800 4450);
FORCEPROP 2 LAST SIG_NAME SW_PVDDCR_CPU0_P0_PH1
J 0
(-5685 4460);
DISPLAY 0.489362 (-5685 4460);
FORCEPROP 2 LASTPROP $XRERR UNIQUE?
J 0
(-5925 4460);
DISPLAY 0.638298 (-5925 4460);
PAINT MONO (-5925 4460);
DISPLAY INVISIBLE (-5925 4460);
WIRE 16 -1 (-5800 4700)(-4950 4700);
FORCEPROP 2 LAST SIG_NAME SW_PVDDCR_CPU0_P0_BOOT1
J 0
(-5685 4725);
DISPLAY 0.489362 (-5685 4725);
FORCEPROP 2 LASTPROP $XRERR UNIQUE?
J 0
(-5925 4725);
DISPLAY 0.638298 (-5925 4725);
PAINT MONO (-5925 4725);
DISPLAY INVISIBLE (-5925 4725);
WIRE 16 -1 (-3525 5325)(-3525 5400);
WIRE 16 -1 (-3175 5400)(-3525 5400);
WIRE 16 -1 (-3525 5400)(-3950 5400);
WIRE 16 -1 (-4025 5400)(-3950 5400);
WIRE 16 -1 (-3950 5325)(-3950 5400);
WIRE 16 -1 (-4025 5450)(-4025 5400);
WIRE 16 -1 (-4025 5400)(-4275 5400);
WIRE 16 -1 (-4275 5400)(-4275 5325);
WIRE 16 -1 (-4575 5400)(-4275 5400);
WIRE 16 -1 (-4575 5400)(-4575 5325);
WIRE 16 -1 (-4900 5400)(-4575 5400);
WIRE 16 -1 (-4900 5325)(-4900 5400);
WIRE 16 -1 (-5225 5400)(-4900 5400);
WIRE 16 -1 (-5225 5325)(-5225 5400);
WIRE 16 -1 (-5550 5400)(-5225 5400);
WIRE 16 -1 (-5550 5325)(-5550 5400);
WIRE 16 -1 (-5700 5400)(-5550 5400);
WIRE 16 -1 (-5700 5400)(-5700 5000);
WIRE 16 -1 (-5700 5000)(-5700 4950);
WIRE 16 -1 (-5800 5000)(-5700 5000);
WIRE 16 -1 (-5700 4950)(-5800 4950);
WIRE 16 -1 (-4000 4700)(-4000 4675);
WIRE 16 -1 (-4750 4700)(-4000 4700);
FORCEPROP 2 LAST SIG_NAME SW_PVDDCR_CPU0_P0_BOOT1_RC
J 2
(-4035 4710);
DISPLAY 0.489362 (-4035 4710);
FORCEPROP 2 LASTPROP $XRERR UNIQUE?
J 0
(-4275 4710);
DISPLAY 0.638298 (-4275 4710);
PAINT MONO (-4275 4710);
DISPLAY INVISIBLE (-4275 4710);
WIRE 16 -1 (-5775 1950)(-4825 1950);
FORCEPROP 2 LAST SIG_NAME SW_PVDDCR_CPU0_P0_BOOT2
J 0
(-5660 1960);
DISPLAY 0.489362 (-5660 1960);
FORCEPROP 2 LASTPROP $XRERR UNIQUE?
J 0
(-5900 1960);
DISPLAY 0.638298 (-5900 1960);
PAINT MONO (-5900 1960);
DISPLAY INVISIBLE (-5900 1960);
WIRE 16 -1 (-3750 1950)(-3750 1925);
WIRE 16 -1 (-4625 1950)(-3750 1950);
FORCEPROP 2 LAST SIG_NAME SW_PVDDCR_CPU0_P0_BOOT2_RC
J 2
(-3785 1960);
DISPLAY 0.489362 (-3785 1960);
FORCEPROP 2 LASTPROP $XRERR UNIQUE?
J 0
(-4025 1960);
DISPLAY 0.638298 (-4025 1960);
PAINT MONO (-4025 1960);
DISPLAY INVISIBLE (-4025 1960);
WIRE 16 -1 (-8200 4250)(-8025 4250);
WIRE 16 -1 (-6650 4250)(-8025 4250);
FORCEPROP 2 LAST SIG_NAME PVDDCR_CPU0_P0_VCCS
J 2
(-6710 4260);
DISPLAY 0.489362 (-6710 4260);
WIRE 16 -1 (-8025 4175)(-8025 4250);
WIRE 16 -1 (-5625 3900)(-5625 3850);
WIRE 16 -1 (-5625 3900)(-5800 3900);
WIRE 16 -1 (-5625 3800)(-5625 3850);
WIRE 16 -1 (-5800 3850)(-5625 3850);
WIRE 16 -1 (-5625 3750)(-5625 3800);
WIRE 16 -1 (-5800 3800)(-5625 3800);
WIRE 16 -1 (-5625 3675)(-5625 3750);
WIRE 16 -1 (-5800 3750)(-5625 3750);
WIRE 16 -1 (-7650 2550)(-7650 2675);
WIRE 16 -1 (-7300 2675)(-7650 2675);
WIRE 16 -1 (-7650 2800)(-7650 2675);
WIRE 16 -1 (-6975 2675)(-7300 2675);
WIRE 16 -1 (-7300 2575)(-7300 2675);
WIRE 16 -1 (-6975 2250)(-6975 2675);
WIRE 16 -1 (-6975 2250)(-6625 2250);
WIRE 16 -1 (-7650 2125)(-7175 2125);
WIRE 16 -1 (-7650 2350)(-7650 2125);
WIRE 16 -1 (-7650 2125)(-7650 2050);
WIRE 16 -1 (-7175 2125)(-7175 1950);
FORCEPROP 2 LAST SIG_NAME PVDDCR_CPU0_P0_VCC2
J 2
(-6710 1960);
DISPLAY 0.489362 (-6710 1960);
FORCEPROP 2 LASTPROP $XRERR UNIQUE?
J 0
(-6950 1960);
DISPLAY 0.638298 (-6950 1960);
PAINT MONO (-6950 1960);
DISPLAY INVISIBLE (-6950 1960);
WIRE 16 -1 (-7175 1950)(-6625 1950);
WIRE 16 -1 (-7175 1950)(-7175 1750);
WIRE 16 -1 (-7175 1750)(-6625 1750);
WIRE 16 -1 (-4650 1600)(-3475 1600);
WIRE 16 -1 (-4650 1600)(-4650 1525);
WIRE 16 -1 (-5775 1600)(-4650 1600);
FORCEPROP 2 LAST SIG_NAME SW_PVDDCR_CPU0_P0_SW2
J 0
(-5660 1610);
DISPLAY 0.489362 (-5660 1610);
FORCEPROP 2 LASTPROP $XRERR UNIQUE?
J 0
(-5900 1610);
DISPLAY 0.638298 (-5900 1610);
PAINT MONO (-5900 1610);
DISPLAY INVISIBLE (-5900 1610);
WIRE 16 -1 (-3750 1725)(-3750 1700);
WIRE 16 -1 (-3750 1700)(-5775 1700);
FORCEPROP 2 LAST SIG_NAME SW_PVDDCR_CPU0_P0_PH2
J 0
(-5660 1710);
DISPLAY 0.489362 (-5660 1710);
FORCEPROP 2 LASTPROP $XRERR UNIQUE?
J 0
(-5900 1710);
DISPLAY 0.638298 (-5900 1710);
PAINT MONO (-5900 1710);
DISPLAY INVISIBLE (-5900 1710);
WIRE 17 273 (-1425 2225)(-1425 3325);
WIRE 17 273 (-3350 2225)(-1425 2225);
WIRE 17 273 (-1425 3325)(-3350 3325);
WIRE 17 273 (-3350 3325)(-3350 2225);
WIRE 16 -1 (-1900 2700)(-1900 2550);
WIRE 16 -1 (-1900 2550)(-1875 2550);
WIRE 16 -1 (-1900 2550)(-2175 2550);
WIRE 16 -1 (-2175 2550)(-2175 2700);
WIRE 16 -1 (-2500 2550)(-2175 2550);
WIRE 16 -1 (-1875 2475)(-1875 2550);
WIRE 16 -1 (-2500 2700)(-2500 2550);
WIRE 16 -1 (-2825 2550)(-2500 2550);
WIRE 16 -1 (-2825 2700)(-2825 2550);
WIRE 16 -1 (-3175 2550)(-2825 2550);
WIRE 16 -1 (-3175 2700)(-3175 2550);
WIRE 16 -1 (-1900 3000)(-1875 3000);
WIRE 16 -1 (-1900 2900)(-1900 3000);
WIRE 16 -1 (-1900 3000)(-2175 3000);
WIRE 16 -1 (-1875 3050)(-1875 3000);
WIRE 16 -1 (-2175 2900)(-2175 3000);
WIRE 16 -1 (-2500 3000)(-2175 3000);
WIRE 16 -1 (-2500 2900)(-2500 3000);
WIRE 16 -1 (-2825 3000)(-2500 3000);
WIRE 16 -1 (-2825 2900)(-2825 3000);
WIRE 16 -1 (-3175 3000)(-2825 3000);
WIRE 16 -1 (-3175 2900)(-3175 3000);
WIRE 16 -1 (-775 4475)(-775 4350);
WIRE 16 -1 (-775 4350)(-775 4250);
WIRE 16 -1 (-775 4350)(-1175 4350);
WIRE 16 -1 (-1175 4350)(-1175 4275);
WIRE 16 -1 (-1175 4350)(-1625 4350);
WIRE 16 -1 (-1625 4350)(-1625 4275);
WIRE 16 -1 (-1625 4350)(-2000 4350);
WIRE 16 -1 (-2000 4275)(-2000 4350);
WIRE 16 -1 (-2125 4350)(-2000 4350);
WIRE 16 -1 (-2850 4350)(-2125 4350);
WIRE 16 -1 (-2125 4350)(-2125 3400);
WIRE 16 -1 (-2125 3400)(-4275 3400);
WIRE 16 -1 (-4300 4100)(-3650 4100);
FORCEPROP 2 LAST SIG_NAME IND_CPU0_P0_CPL5
J 0
(-4235 4135);
DISPLAY 0.489362 (-4235 4135);
WIRE 16 -1 (-2850 4100)(-2375 4100);
FORCEPROP 2 LAST SIG_NAME IND_CPU0_P0_CPL1
J 0
(-2785 4110);
DISPLAY 0.489362 (-2785 4110);
WIRE 16 -1 (-2700 5450)(-2700 5400);
WIRE 16 -1 (-2700 5400)(-2700 5350);
WIRE 16 -1 (-2700 5400)(-2975 5400);
WIRE 16 -1 (-4825 4075)(-4825 3825);
FORCEPROP 2 LAST SIG_NAME SW_PVDDCR_CPU0_P0_SW1_RC
J 0
(-4785 3910);
DISPLAY 0.489362 (-4785 3910);
FORCEPROP 2 LASTPROP $XRERR UNIQUE?
J 0
(-5025 3910);
DISPLAY 0.638298 (-5025 3910);
PAINT MONO (-5025 3910);
DISPLAY INVISIBLE (-5025 3910);
WIRE 16 -1 (-6650 4350)(-7300 4350);
FORCEPROP 2 LAST SIG_NAME PVDDCR_CPU0_P0_IMON1
J 2
(-6710 4360);
DISPLAY 0.489362 (-6710 4360);
WIRE 16 -1 (-5800 4350)(-4825 4350);
FORCEPROP 2 LAST SIG_NAME SW_PVDDCR_CPU0_P0_SW1
J 0
(-5685 4360);
DISPLAY 0.489362 (-5685 4360);
FORCEPROP 2 LASTPROP $XRERR UNIQUE?
J 0
(-5925 4360);
DISPLAY 0.638298 (-5925 4360);
PAINT MONO (-5925 4360);
DISPLAY INVISIBLE (-5925 4360);
WIRE 16 -1 (-4825 4350)(-3650 4350);
WIRE 16 -1 (-4825 4350)(-4825 4275);
WIRE 16 -1 (-5775 1300)(-5250 1300);
FORCEPROP 2 LAST SIG_NAME NC_PVDDCR_CPU0_P0_GL1_2
J 0
(-5660 1310);
DISPLAY 0.489362 (-5660 1310);
FORCEPROP 2 LASTPROP $XRERR UNIQUE?
J 0
(-5220 1300);
DISPLAY 0.638298 (-5220 1300);
PAINT MONO (-5220 1300);
DISPLAY INVISIBLE (-5220 1300);
WIRE 16 -1 (-775 4050)(-775 3950);
WIRE 16 -1 (-775 3850)(-775 3950);
WIRE 16 -1 (-775 3950)(-1175 3950);
WIRE 16 -1 (-1175 4075)(-1175 3950);
WIRE 16 -1 (-1175 3950)(-1625 3950);
WIRE 16 -1 (-1625 4075)(-1625 3950);
WIRE 16 -1 (-2000 3950)(-1625 3950);
WIRE 16 -1 (-2000 3950)(-2000 4075);
WIRE 16 -1 (-1725 1600)(-1925 1600);
WIRE 16 -1 (-1725 1600)(-1300 1600);
WIRE 16 -1 (-1725 1600)(-1725 1525);
WIRE 16 -1 (-1925 1600)(-1925 675);
WIRE 16 -1 (-2675 1600)(-1925 1600);
WIRE 16 -1 (-1925 675)(-4150 675);
WIRE 16 -1 (-1300 1700)(-1300 1600);
WIRE 16 -1 (-1300 1600)(-1300 1525);
WIRE 16 -1 (-1300 1325)(-1300 1200);
WIRE 16 -1 (-1300 1125)(-1300 1200);
WIRE 16 -1 (-1300 1200)(-1725 1200);
WIRE 16 -1 (-1725 1325)(-1725 1200);
WIRE 16 -1 (-5775 1000)(-5625 1000);
WIRE 16 -1 (-5625 1000)(-5625 1050);
WIRE 16 -1 (-5625 925)(-5625 1000);
WIRE 16 -1 (-5625 1050)(-5625 1100);
WIRE 16 -1 (-5775 1050)(-5625 1050);
WIRE 16 -1 (-5625 1150)(-5625 1100);
WIRE 16 -1 (-5775 1100)(-5625 1100);
WIRE 16 -1 (-5625 1150)(-5775 1150);
WIRE 16 -1 (-2225 1350)(-2675 1350);
FORCEPROP 2 LAST SIG_NAME IND_CPU0_P0_CPL2
J 0
(-2610 1360);
DISPLAY 0.489362 (-2610 1360);
WIRE 16 -1 (-3900 1350)(-3475 1350);
FORCEPROP 2 LAST SIG_NAME IND_CPU0_P0_CPL1
J 0
(-3885 1360);
DISPLAY 0.489362 (-3885 1360);
WIRE 16 -1 (-6625 1000)(-7225 1000);
FORCEPROP 2 LAST SIG_NAME PVDDCR_CPU0_P0_PWM2
J 2
(-6710 1010);
DISPLAY 0.489362 (-6710 1010);
WIRE 16 -1 (-6650 3750)(-7250 3750);
FORCEPROP 2 LAST SIG_NAME PVDDCR_CPU0_P0_PWM1
J 2
(-6710 3760);
DISPLAY 0.489362 (-6710 3760);
WIRE 16 -1 (-5800 4000)(-5275 4000);
FORCEPROP 2 LAST SIG_NAME NC_PVDDCR_CPU0_P0_GL2_1
J 0
(-5675 4010);
DISPLAY 0.489362 (-5675 4010);
FORCEPROP 2 LASTPROP $XRERR UNIQUE?
J 0
(-5245 4000);
DISPLAY 0.638298 (-5245 4000);
PAINT MONO (-5245 4000);
DISPLAY INVISIBLE (-5245 4000);
WIRE 16 -1 (-5800 4050)(-5275 4050);
FORCEPROP 2 LAST SIG_NAME NC_PVDDCR_CPU0_P0_GL1_1
J 0
(-5675 4060);
DISPLAY 0.489362 (-5675 4060);
FORCEPROP 2 LASTPROP $XRERR UNIQUE?
J 0
(-5245 4050);
DISPLAY 0.638298 (-5245 4050);
PAINT MONO (-5245 4050);
DISPLAY INVISIBLE (-5245 4050);
WIRE 16 -1 (-6650 4100)(-7100 4100);
FORCEPROP 2 LAST SIG_NAME NC_PVDDCR_CPU0_P0_DNC1
J 2
(-6710 4110);
DISPLAY 0.489362 (-6710 4110);
FORCEPROP 2 LASTPROP $XRERR UNIQUE?
J 0
(-7340 4100);
DISPLAY 0.638298 (-7340 4100);
PAINT MONO (-7340 4100);
DISPLAY INVISIBLE (-7340 4100);
WIRE 16 -1 (-7250 4050)(-6650 4050);
FORCEPROP 2 LAST SIG_NAME PVDDCR_CPU0_P0_LSET1
J 2
(-6710 4060);
DISPLAY 0.489362 (-6710 4060);
FORCEPROP 2 LASTPROP $XRERR UNIQUE?
J 0
(-6950 4060);
DISPLAY 0.638298 (-6950 4060);
PAINT MONO (-6950 4060);
DISPLAY INVISIBLE (-6950 4060);
WIRE 16 -1 (-4650 1325)(-4650 1075);
FORCEPROP 2 LAST SIG_NAME SW_PVDDCR_CPU0_P0_SW2_RC
J 0
(-4610 1160);
DISPLAY 0.489362 (-4610 1160);
FORCEPROP 2 LASTPROP $XRERR UNIQUE?
J 0
(-4850 1160);
DISPLAY 0.638298 (-4850 1160);
PAINT MONO (-4850 1160);
DISPLAY INVISIBLE (-4850 1160);
WIRE 16 -1 (-5775 1250)(-5250 1250);
FORCEPROP 2 LAST SIG_NAME NC_PVDDCR_CPU0_P0_GL2_2
J 0
(-5660 1260);
DISPLAY 0.489362 (-5660 1260);
FORCEPROP 2 LASTPROP $XRERR UNIQUE?
J 0
(-5220 1250);
DISPLAY 0.638298 (-5220 1250);
PAINT MONO (-5220 1250);
DISPLAY INVISIBLE (-5220 1250);
WIRE 16 -1 (-6650 3850)(-7275 3850);
FORCEPROP 2 LAST SIG_NAME PVDDCR_CPU0_P0_TEMP0
J 2
(-6710 3860);
DISPLAY 0.489362 (-6710 3860);
WIRE 16 -1 (-6625 1350)(-7075 1350);
FORCEPROP 2 LAST SIG_NAME NC_PVDDCR_CPU0_P0_DNC2
J 2
(-6685 1360);
DISPLAY 0.489362 (-6685 1360);
FORCEPROP 2 LASTPROP $XRERR UNIQUE?
J 0
(-7315 1350);
DISPLAY 0.638298 (-7315 1350);
PAINT MONO (-7315 1350);
DISPLAY INVISIBLE (-7315 1350);
WIRE 16 -1 (-6625 1600)(-7275 1600);
FORCEPROP 2 LAST SIG_NAME PVDDCR_CPU0_P0_IMON2
J 2
(-6685 1610);
DISPLAY 0.489362 (-6685 1610);
WIRE 16 -1 (-6625 1100)(-7250 1100);
FORCEPROP 2 LAST SIG_NAME PVDDCR_CPU0_P0_TEMP0
J 2
(-6685 1110);
DISPLAY 0.489362 (-6685 1110);
WIRE 16 -1 (-7250 1300)(-6625 1300);
FORCEPROP 2 LAST SIG_NAME PVDDCR_CPU0_P0_LSET2
J 2
(-6685 1310);
DISPLAY 0.489362 (-6685 1310);
FORCEPROP 2 LASTPROP $XRERR UNIQUE?
J 0
(-6925 1310);
DISPLAY 0.638298 (-6925 1310);
PAINT MONO (-6925 1310);
DISPLAY INVISIBLE (-6925 1310);
WIRE 16 -1 (-8000 1425)(-8000 1500);
WIRE 16 -1 (-6625 1500)(-8000 1500);
FORCEPROP 2 LAST SIG_NAME PVDDCR_CPU0_P0_VCCS
J 2
(-6685 1510);
DISPLAY 0.489362 (-6685 1510);
WIRE 16 -1 (-8175 1500)(-8000 1500);
WIRE 16 -1 (-4350 675)(-5025 675);
FORCEPROP 2 LAST SIG_NAME PVDDCR_CPU0_P0_VOS2
J 0
(-5660 1375);
DISPLAY 0.489362 (-5660 1375);
FORCEPROP 2 LASTPROP $XRERR UNIQUE?
J 0
(-5900 1375);
DISPLAY 0.638298 (-5900 1375);
PAINT MONO (-5900 1375);
DISPLAY INVISIBLE (-5900 1375);
WIRE 16 -1 (-5025 675)(-5025 1350);
WIRE 16 -1 (-5775 1350)(-5025 1350);
DOT 1 (-4900 2250);
DOT 1 (-4900 5000);
DOT 1 (-775 4350);
DOT 1 (-1175 4350);
DOT 1 (-1625 4350);
DOT 1 (-2700 5400);
DOT 1 (-2125 4350);
DOT 1 (-3525 5400);
DOT 1 (-3950 5400);
DOT 1 (-4025 5400);
DOT 1 (-3950 5000);
DOT 1 (-4025 5000);
DOT 1 (-775 3950);
DOT 1 (-1175 3950);
DOT 1 (-1625 3950);
DOT 1 (-1900 3000);
DOT 1 (-1900 2550);
DOT 1 (-1300 1600);
DOT 1 (-1300 1200);
DOT 1 (-1725 1600);
DOT 1 (-1925 1600);
DOT 1 (-2175 3000);
DOT 1 (-2825 3000);
DOT 1 (-2175 2550);
DOT 1 (-2500 2550);
DOT 1 (-2825 2550);
DOT 1 (-4275 5400);
DOT 1 (-4575 5400);
DOT 1 (-4900 5400);
DOT 1 (-4575 5000);
DOT 1 (-5225 5400);
DOT 1 (-5550 5400);
DOT 1 (-5700 5000);
DOT 1 (-7625 5450);
DOT 1 (-7800 5450);
DOT 1 (-7975 5450);
DOT 1 (-7225 4700);
DOT 1 (-7975 4875);
DOT 1 (-8025 4250);
DOT 1 (-4275 2650);
DOT 1 (-4575 2650);
DOT 1 (-4275 2250);
DOT 1 (-4575 2250);
DOT 1 (-5625 3850);
DOT 1 (-5625 3800);
DOT 1 (-5625 3750);
DOT 1 (-5225 2650);
DOT 1 (-5225 2250);
DOT 1 (-5675 2250);
DOT 1 (-4650 1600);
DOT 1 (-5625 1100);
DOT 1 (-5625 1050);
DOT 1 (-5625 1000);
DOT 1 (-7300 2675);
DOT 1 (-7650 2675);
DOT 1 (-7650 2125);
DOT 1 (-7175 1950);
DOT 1 (-8000 1500);
DOT 1 (-8275 5450);
DOT 1 (-4825 4350);
DOT 1 (-5550 2650);
DOT 1 (-4275 5000);
DOT 1 (-5225 5000);
DOT 1 (-2000 4350);
DOT 1 (-2500 3000);
DOT 1 (-4900 2650);
FORCENOTE
PC473_1,PC474_2,PC544_3,PC545_4,PC566_5,PC150_6 = EMPTY
(-2050 5525) 0;
DISPLAY LEFT (-2050 5525);
DISPLAY 0.638298 (-2050 5525);
PAINT WHITE (-2050 5525);
FORCENOTE
PR324,PR325,PR350,PR351,PR355,PR433 = EMPTY
(-2050 5600) 0;
DISPLAY LEFT (-2050 5600);
DISPLAY 0.638298 (-2050 5600);
PAINT WHITE (-2050 5600);
FORCENOTE
PR320,PR321,PR346,PR347,PR353,PR431 = CS00002JB13
(-2050 5675) 0;
DISPLAY LEFT (-2050 5675);
DISPLAY 0.638298 (-2050 5675);
PAINT WHITE (-2050 5675);
FORCENOTE
2ND SOURCE:INFENEON BOM
(-2050 5925) 0;
DISPLAY LEFT (-2050 5925);
DISPLAY 1.021277 (-2050 5925);
PAINT WHITE (-2050 5925);
FORCENOTE
PU6,PU43,PU46,PU47,PU48,PU10 = AL021590000/TDA21590
(-2050 5825) 0;
DISPLAY LEFT (-2050 5825);
DISPLAY 0.638298 (-2050 5825);
PAINT WHITE (-2050 5825);
FORCENOTE
PU6,PU43,PU46,PU47,PU48,PU10 = AL099390004/ISL99390FRZ-TR5935
(-2050 6100) 0;
DISPLAY LEFT (-2050 6100);
DISPLAY 0.638298 (-2050 6100);
PAINT WHITE (-2050 6100);
FORCENOTE
BOM NOTE
(-2050 6300) 0;
DISPLAY LEFT (-2050 6300);
DISPLAY 1.595745 (-2050 6300);
PAINT WHITE (-2050 6300);
FORCENOTE
MAIN SOURCE:RENESAS BOM
(-2050 6200) 0;
DISPLAY LEFT (-2050 6200);
DISPLAY 1.021277 (-2050 6200);
PAINT WHITE (-2050 6200);
FORCENOTE
PR322,PR323,PR348,PR349,PR354,PR432 = CS00002JB13
(-2050 5750) 0;
DISPLAY LEFT (-2050 5750);
DISPLAY 0.638298 (-2050 5750);
PAINT WHITE (-2050 5750);
FORCENOTE
3RD SOURCE:MPS BOM
(-2050 5325) 0;
DISPLAY LEFT (-2050 5325);
DISPLAY 1.021277 (-2050 5325);
PAINT WHITE (-2050 5325);
FORCENOTE
PU6,PU43,PU46,PU47,PU48,PU10 = AL087000A03/MP87000GMJTH-C11D-Z
(-2050 5225) 0;
DISPLAY LEFT (-2050 5225);
DISPLAY 0.638298 (-2050 5225);
PAINT WHITE (-2050 5225);
FORCENOTE
PR446,PR322,PR323,PR348,PR349,PR354,PR432 = CS00002JB13
(-2050 5150) 0;
DISPLAY LEFT (-2050 5150);
DISPLAY 0.638298 (-2050 5150);
PAINT WHITE (-2050 5150);
FORCENOTE
PR445,PR324,PR325,PR350,PR351,PR355,PR433 = EMPTY
(-2050 5075) 0;
DISPLAY LEFT (-2050 5075);
DISPLAY 0.638298 (-2050 5075);
PAINT WHITE (-2050 5075);
FORCENOTE
PC473_1,PC474_2,PC544_3,PC545_4,PC566_5,PC150_6 = EMPTY
(-2050 5000) 0;
DISPLAY LEFT (-2050 5000);
DISPLAY 0.638298 (-2050 5000);
PAINT WHITE (-2050 5000);
FORCENOTE
2ND=CC72703MD39
(-3700 4800) 0;
DISPLAY LEFT (-3700 4800);
DISPLAY 0.638298 (-3700 4800);
PAINT WHITE (-3700 4800);
FORCENOTE
PGL6303.151HLT
(-2825 4650) 0;
DISPLAY LEFT (-2825 4650);
DISPLAY 0.638298 (-2825 4650);
PAINT WHITE (-2825 4650);
FORCENOTE
ISAT:70A@100C
(-2825 4600) 0;
DISPLAY LEFT (-2825 4600);
DISPLAY 0.638298 (-2825 4600);
PAINT WHITE (-2825 4600);
FORCENOTE
11.0*7.5*12.5
(-2825 4550) 0;
DISPLAY LEFT (-2825 4550);
DISPLAY 0.638298 (-2825 4550);
PAINT WHITE (-2825 4550);
FORCENOTE
DCR=1-4,0.105M OHM
(-2825 4500) 0;
DISPLAY LEFT (-2825 4500);
DISPLAY 0.638298 (-2825 4500);
PAINT WHITE (-2825 4500);
FORCENOTE
2ND=CV+15^0TZ01
(-2825 4400) 0;
DISPLAY LEFT (-2825 4400);
DISPLAY 0.638298 (-2825 4400);
PAINT WHITE (-2825 4400);
FORCENOTE
DCR=2-3,0.27M OHM
(-2825 4450) 0;
DISPLAY LEFT (-2825 4450);
DISPLAY 0.638298 (-2825 4450);
PAINT WHITE (-2825 4450);
FORCENOTE
3RD=CVA50^0MZ08
(-3250 5075) 0;
DISPLAY LEFT (-3250 5075);
DISPLAY 0.638298 (-3250 5075);
PAINT WHITE (-3250 5075);
FORCENOTE
PG2292.500HLT
(-3250 5325) 0;
DISPLAY LEFT (-3250 5325);
DISPLAY 0.638298 (-3250 5325);
PAINT WHITE (-3250 5325);
FORCENOTE
MAIN=CH122KM8801
(-2525 2350) 0;
DISPLAY LEFT (-2525 2350);
DISPLAY 0.638298 (-2525 2350);
PAINT WHITE (-2525 2350);
FORCENOTE
ESR=9.0M OHM
(-2525 2450) 0;
DISPLAY LEFT (-2525 2450);
DISPLAY 0.638298 (-2525 2450);
PAINT WHITE (-2525 2450);
FORCENOTE
7.3*4.3*1.9
(-2525 2400) 0;
DISPLAY LEFT (-2525 2400);
DISPLAY 0.638298 (-2525 2400);
PAINT WHITE (-2525 2400);
FORCENOTE
PGL6303.151HLT
(-2650 1900) 0;
DISPLAY LEFT (-2650 1900);
DISPLAY 0.638298 (-2650 1900);
PAINT WHITE (-2650 1900);
FORCENOTE
ISAT:70A@100C
(-2650 1850) 0;
DISPLAY LEFT (-2650 1850);
DISPLAY 0.638298 (-2650 1850);
PAINT WHITE (-2650 1850);
FORCENOTE
DCR=2-3,0.27M OHM
(-2650 1700) 0;
DISPLAY LEFT (-2650 1700);
DISPLAY 0.638298 (-2650 1700);
PAINT WHITE (-2650 1700);
FORCENOTE
2ND=CV+15^0TZ01
(-2650 1650) 0;
DISPLAY LEFT (-2650 1650);
DISPLAY 0.638298 (-2650 1650);
PAINT WHITE (-2650 1650);
FORCENOTE
DCR=1-4,0.105M OHM
(-2650 1750) 0;
DISPLAY LEFT (-2650 1750);
DISPLAY 0.638298 (-2650 1750);
PAINT WHITE (-2650 1750);
FORCENOTE
11.0*7.5*12.5
(-2650 1800) 0;
DISPLAY LEFT (-2650 1800);
DISPLAY 0.638298 (-2650 1800);
PAINT WHITE (-2650 1800);
FORCENOTE
PVDDCR_CPU0_P0_PHASE1
(-6975 5825) 0;
DISPLAY LEFT (-6975 5825);
DISPLAY 1.595745 (-6975 5825);
PAINT WHITE (-6975 5825);
FORCENOTE
PVDDCR_CPU0_P0_PHASE2
(-6750 2925) 0;
DISPLAY LEFT (-6750 2925);
DISPLAY 1.595745 (-6750 2925);
PAINT WHITE (-6750 2925);
FORCENOTE
ISAT:70A@100C
(-3250 5275) 0;
DISPLAY LEFT (-3250 5275);
DISPLAY 0.638298 (-3250 5275);
PAINT WHITE (-3250 5275);
FORCENOTE
6.0*6.1*7.0
(-3250 5225) 0;
DISPLAY LEFT (-3250 5225);
DISPLAY 0.638298 (-3250 5225);
PAINT WHITE (-3250 5225);
FORCENOTE
DCR=0.09M OHM
(-3250 5175) 0;
DISPLAY LEFT (-3250 5175);
DISPLAY 0.638298 (-3250 5175);
PAINT WHITE (-3250 5175);
FORCENOTE
2ND=CVA50^0MZ07
(-3250 5125) 0;
DISPLAY LEFT (-3250 5125);
DISPLAY 0.638298 (-3250 5125);
PAINT WHITE (-3250 5125);
FORCENOTE
ESR=10M OHM
(-3700 4950) 0;
DISPLAY LEFT (-3700 4950);
DISPLAY 0.638298 (-3700 4950);
PAINT WHITE (-3700 4950);
FORCENOTE
IRIPPLE:5.08A
(-3700 4900) 0;
DISPLAY LEFT (-3700 4900);
DISPLAY 0.638298 (-3700 4900);
PAINT WHITE (-3700 4900);
FORCENOTE
6.3*8
(-3700 4850) 0;
DISPLAY LEFT (-3700 4850);
DISPLAY 0.638298 (-3700 4850);
PAINT WHITE (-3700 4850);
QUIT
